G04 ================== begin FILE IDENTIFICATION RECORD ==================*
G04 Layout Name:  t6m_pdb_d_0928_1400_274.brd*
G04 Film Name:    vcc*
G04 File Format:  Gerber RS274X*
G04 File Origin:  Cadence Allegro 16.3-S048*
G04 Origin Date:  Tue Nov 26 11:01:51 2013*
G04 *
G04 Layer:  DRAWING FORMAT/TITLE_BLOCK*
G04 Layer:  VIA CLASS/VCC*
G04 Layer:  PIN/VCC*
G04 Layer:  MANUFACTURING/PHOTOPLOT_OUTLINE*
G04 Layer:  ETCH/VCC*
G04 Layer:  DRAWING FORMAT/TITLE_DATA_VCC*
G04 *
G04 Offset:    (0.00 0.00)*
G04 Mirror:    No*
G04 Mode:      Negative*
G04 Rotation:  0*
G04 FullContactRelief:  No*
G04 UndefLineWidth:     6.00*
G04 ================== end FILE IDENTIFICATION RECORD ====================*
%FSLAX25Y25*MOIN*%
%IR0*IPPOS*OFA0.00000B0.00000*MIA0B0*SFA1.00000B1.00000*%
%ADD11C,.03*%
%ADD28C,.04*%
%ADD31C,.05*%
%ADD22C,.042*%
%ADD16C,.06*%
%ADD25C,.064*%
%ADD15C,.083*%
%ADD13C,.056*%
%ADD17C,.048*%
%AMMACRO29*
4,1,36,0.0,.009,
.001563,.008863,
.003078,.008457,
.0045,.007794,
.005785,.006894,
.006894,.005785,
.007794,.0045,
.008457,.003078,
.008863,.001563,
.009,0.0,
.008863,-.001563,
.008457,-.003078,
.007794,-.0045,
.006894,-.005785,
.005785,-.006894,
.0045,-.007794,
.003078,-.008457,
.001563,-.008863,
0.0,-.009,
-.001563,-.008863,
-.003078,-.008457,
-.0045,-.007794,
-.005785,-.006894,
-.006894,-.005785,
-.007794,-.0045,
-.008457,-.003078,
-.008863,-.001563,
-.009,0.0,
-.008863,.001563,
-.008457,.003078,
-.007794,.0045,
-.006894,.005785,
-.005785,.006894,
-.0045,.007794,
-.003078,.008457,
-.001563,.008863,
0.0,.009,
90.*
%
%ADD29MACRO29*%
%ADD20C,.077*%
%ADD10C,.059*%
%AMMACRO30*
4,1,36,0.0,.009,
.001563,.008863,
.003078,.008457,
.0045,.007794,
.005785,.006894,
.006894,.005785,
.007794,.0045,
.008457,.003078,
.008863,.001563,
.009,0.0,
.008863,-.001563,
.008457,-.003078,
.007794,-.0045,
.006894,-.005785,
.005785,-.006894,
.0045,-.007794,
.003078,-.008457,
.001563,-.008863,
0.0,-.009,
-.001563,-.008863,
-.003078,-.008457,
-.0045,-.007794,
-.005785,-.006894,
-.006894,-.005785,
-.007794,-.0045,
-.008457,-.003078,
-.008863,-.001563,
-.009,0.0,
-.008863,.001563,
-.008457,.003078,
-.007794,.0045,
-.006894,.005785,
-.005785,.006894,
-.0045,.007794,
-.003078,.008457,
-.001563,.008863,
0.0,.009,
0.0*
%
%ADD30MACRO30*%
%ADD37O,.235X.274*%
%ADD19C,.125*%
%ADD12C,.162*%
%ADD36C,.235*%
%ADD38C,.345*%
%ADD27C,.129*%
%ADD14C,.156*%
%AMMACRO18*
4,1,36,0.0,.013,
-.002257,.012803,
-.004446,.012216,
-.0065,.011258,
-.008356,.009959,
-.009959,.008356,
-.011258,.0065,
-.012216,.004446,
-.012803,.002257,
-.013,0.0,
-.012803,-.002257,
-.012216,-.004446,
-.011258,-.0065,
-.009959,-.008356,
-.008356,-.009959,
-.0065,-.011258,
-.004446,-.012216,
-.002257,-.012803,
0.0,-.013,
.002257,-.012803,
.004446,-.012216,
.0065,-.011258,
.008356,-.009959,
.009959,-.008356,
.011258,-.0065,
.012216,-.004446,
.012803,-.002257,
.013,0.0,
.012803,.002257,
.012216,.004446,
.011258,.0065,
.009959,.008356,
.008356,.009959,
.0065,.011258,
.004446,.012216,
.002257,.012803,
0.0,.013,
270.*
%
%ADD18MACRO18*%
%AMMACRO35*
4,1,36,0.0,.009,
.001563,.008863,
.003078,.008457,
.0045,.007794,
.005785,.006894,
.006894,.005785,
.007794,.0045,
.008457,.003078,
.008863,.001563,
.009,0.0,
.008863,-.001563,
.008457,-.003078,
.007794,-.0045,
.006894,-.005785,
.005785,-.006894,
.0045,-.007794,
.003078,-.008457,
.001563,-.008863,
0.0,-.009,
-.001563,-.008863,
-.003078,-.008457,
-.0045,-.007794,
-.005785,-.006894,
-.006894,-.005785,
-.007794,-.0045,
-.008457,-.003078,
-.008863,-.001563,
-.009,0.0,
-.008863,.001563,
-.008457,.003078,
-.007794,.0045,
-.006894,.005785,
-.005785,.006894,
-.0045,.007794,
-.003078,.008457,
-.001563,.008863,
0.0,.009,
270.*
%
%ADD35MACRO35*%
%AMMACRO33*
4,1,36,0.0,.009,
.001563,.008863,
.003078,.008457,
.0045,.007794,
.005785,.006894,
.006894,.005785,
.007794,.0045,
.008457,.003078,
.008863,.001563,
.009,0.0,
.008863,-.001563,
.008457,-.003078,
.007794,-.0045,
.006894,-.005785,
.005785,-.006894,
.0045,-.007794,
.003078,-.008457,
.001563,-.008863,
0.0,-.009,
-.001563,-.008863,
-.003078,-.008457,
-.0045,-.007794,
-.005785,-.006894,
-.006894,-.005785,
-.007794,-.0045,
-.008457,-.003078,
-.008863,-.001563,
-.009,0.0,
-.008863,.001563,
-.008457,.003078,
-.007794,.0045,
-.006894,.005785,
-.005785,.006894,
-.0045,.007794,
-.003078,.008457,
-.001563,.008863,
0.0,.009,
180.*
%
%ADD33MACRO33*%
%AMMACRO34*
4,1,36,0.0,.014,
.002431,.013787,
.004788,.013156,
.007,.012124,
.008999,.010725,
.010725,.008999,
.012124,.007,
.013156,.004788,
.013787,.002431,
.014,0.0,
.013787,-.002431,
.013156,-.004788,
.012124,-.007,
.010725,-.008999,
.008999,-.010725,
.007,-.012124,
.004788,-.013156,
.002431,-.013787,
0.0,-.014,
-.002431,-.013787,
-.004788,-.013156,
-.007,-.012124,
-.008999,-.010725,
-.010725,-.008999,
-.012124,-.007,
-.013156,-.004788,
-.013787,-.002431,
-.014,0.0,
-.013787,.002431,
-.013156,.004788,
-.012124,.007,
-.010725,.008999,
-.008999,.010725,
-.007,.012124,
-.004788,.013156,
-.002431,.013787,
0.0,.014,
180.*
%
%ADD34MACRO34*%
%ADD23C,.188*%
%AMMACRO24*
4,1,36,0.0,.004,
.000695,.003939,
.001368,.003759,
.002,.003464,
.002571,.003064,
.003064,.002571,
.003464,.002,
.003759,.001368,
.003939,.000695,
.004,0.0,
.003939,-.000695,
.003759,-.001368,
.003464,-.002,
.003064,-.002571,
.002571,-.003064,
.002,-.003464,
.001368,-.003759,
.000695,-.003939,
0.0,-.004,
-.000695,-.003939,
-.001368,-.003759,
-.002,-.003464,
-.002571,-.003064,
-.003064,-.002571,
-.003464,-.002,
-.003759,-.001368,
-.003939,-.000695,
-.004,0.0,
-.003939,.000695,
-.003759,.001368,
-.003464,.002,
-.003064,.002571,
-.002571,.003064,
-.002,.003464,
-.001368,.003759,
-.000695,.003939,
0.0,.004,
0.0*
%
%ADD24MACRO24*%
%AMMACRO26*
4,1,16,.02584,.01524,
.028094,.010521,
.029494,.005483,
.029998,.000278,
.029591,-.004935,
.028284,-.009999,
.026118,-.014758,
.02584,-.01524,
.03092,-.02032,
.033979,-.014642,
.036005,-.008519,
.036938,-.002138,
.036748,.004309,
.035441,.010625,
.033058,.016618,
.03092,.02032,
.02584,.01524,
270.*
4,1,16,.01524,-.02584,
.010521,-.028094,
.005483,-.029494,
.000278,-.029998,
-.004935,-.029591,
-.009999,-.028284,
-.014758,-.026118,
-.01524,-.02584,
-.02032,-.03092,
-.014642,-.033979,
-.008519,-.036005,
-.002138,-.036938,
.004309,-.036748,
.010625,-.035441,
.016618,-.033058,
.02032,-.03092,
.01524,-.02584,
270.*
4,1,16,-.02584,-.01524,
-.028094,-.010521,
-.029494,-.005483,
-.029998,-.000278,
-.029591,.004935,
-.028284,.009999,
-.026118,.014758,
-.02584,.01524,
-.03092,.02032,
-.033979,.014642,
-.036005,.008519,
-.036938,.002138,
-.036748,-.004309,
-.035441,-.010625,
-.033058,-.016618,
-.03092,-.02032,
-.02584,-.01524,
270.*
4,1,16,-.01524,.02584,
-.010521,.028094,
-.005483,.029494,
-.000278,.029998,
.004935,.029591,
.009999,.028284,
.014758,.026118,
.01524,.02584,
.02032,.03092,
.014642,.033979,
.008519,.036005,
.002138,.036938,
-.004309,.036748,
-.010625,.035441,
-.016618,.033058,
-.02032,.03092,
-.01524,.02584,
270.*
%
%ADD26MACRO26*%
%AMMACRO32*
4,1,15,.02291,.0123,
.024698,.008135,
.025735,.003723,
.025991,-.000803,
.025456,-.005304,
.024149,-.009644,
.02291,-.0123,
.02803,-.01742,
.030629,-.012288,
.032298,-.006783,
.032985,-.001071,
.03267,.004673,
.031362,.010275,
.029101,.015565,
.02803,.01742,
.02291,.0123,
180.*
4,1,15,.0123,-.02291,
.008135,-.024698,
.003723,-.025735,
-.000803,-.025991,
-.005304,-.025456,
-.009644,-.024149,
-.0123,-.02291,
-.01742,-.02803,
-.012288,-.030629,
-.006783,-.032298,
-.001071,-.032985,
.004673,-.03267,
.010275,-.031362,
.015565,-.029101,
.01742,-.02803,
.0123,-.02291,
180.*
4,1,15,-.02291,-.0123,
-.024698,-.008135,
-.025735,-.003723,
-.025991,.000803,
-.025456,.005304,
-.024149,.009644,
-.02291,.0123,
-.02803,.01742,
-.030629,.012288,
-.032298,.006783,
-.032985,.001071,
-.03267,-.004673,
-.031362,-.010275,
-.029101,-.015565,
-.02803,-.01742,
-.02291,-.0123,
180.*
4,1,15,-.0123,.02291,
-.008135,.024698,
-.003723,.025735,
.000803,.025991,
.005304,.025456,
.009644,.024149,
.0123,.02291,
.01742,.02803,
.012288,.030629,
.006783,.032298,
.001071,.032985,
-.004673,.03267,
-.010275,.031362,
-.015565,.029101,
-.01742,.02803,
-.0123,.02291,
180.*
%
%ADD32MACRO32*%
%AMMACRO21*
4,1,17,.03056,.01996,
.033562,.01435,
.035544,.008304,
.036446,.002006,
.03624,-.004353,
.034934,-.01058,
.032566,-.016486,
.03056,-.01996,
.0356,-.025,
.0394,-.018438,
.042004,-.011316,
.043331,-.003851,
.043341,.003732,
.042034,.011201,
.039451,.018331,
.035668,.024903,
.0356,.025,
.03056,.01996,
270.*
4,1,17,.01996,-.03056,
.01435,-.033562,
.008304,-.035544,
.002006,-.036446,
-.004353,-.03624,
-.01058,-.034934,
-.016486,-.032566,
-.01996,-.03056,
-.025,-.0356,
-.018438,-.0394,
-.011316,-.042004,
-.003851,-.043331,
.003732,-.043341,
.011201,-.042034,
.018331,-.039451,
.024903,-.035668,
.025,-.0356,
.01996,-.03056,
270.*
4,1,17,-.03056,-.01996,
-.033562,-.01435,
-.035544,-.008304,
-.036446,-.002006,
-.03624,.004353,
-.034934,.01058,
-.032566,.016486,
-.03056,.01996,
-.0356,.025,
-.0394,.018438,
-.042004,.011316,
-.043331,.003851,
-.043341,-.003732,
-.042034,-.011201,
-.039451,-.018331,
-.035668,-.024903,
-.0356,-.025,
-.03056,-.01996,
270.*
4,1,17,-.01996,.03056,
-.01435,.033562,
-.008304,.035544,
-.002006,.036446,
.004353,.03624,
.01058,.034934,
.016486,.032566,
.01996,.03056,
.025,.0356,
.018438,.0394,
.011316,.042004,
.003851,.043331,
-.003732,.043341,
-.011201,.042034,
-.018331,.039451,
-.024903,.035668,
-.025,.0356,
-.01996,.03056,
270.*
%
%ADD21MACRO21*%
%ADD39C,.006*%
%ADD42C,.41402*%
%ADD40C,.4043*%
%ADD49C,.24506*%
%ADD48C,.13238*%
%ADD45C,.16406*%
%ADD47C,.12717*%
%ADD43C,.13266*%
%ADD46C,.15806*%
%ADD44C,.35606*%
%ADD41C,.41378*%
G75*
%LPD*%
G75*
G36*
G01X-723776Y-489221D02*
X1782976D01*
Y2987387D01*
X-723776D01*
Y-489221D01*
G37*
%LPC*%
G75*
G36*
G01X104331Y4000D02*
G02X102425Y5906I0J1906D01*
G01Y9843D01*
G03X92520Y19748I-9905J0D01*
G01X77515D01*
G03X72923I-2296J-996D01*
G01X26549D01*
G02X26217Y19874I0J500D01*
G03X24221I-998J-1122D01*
G02X23889Y19748I-332J374D01*
G01X5906D01*
G02X4000Y21654I0J1906D01*
G01Y50707D01*
X4124Y51033D01*
X4173Y51094D01*
G03Y52974I-1172J940D01*
G01X4124Y53035D01*
X4000Y53361D01*
Y54967D01*
G02X5841Y55509I1000J1D01*
G03Y64397I6894J4444D01*
G02X4000Y64939I-841J541D01*
G01Y98707D01*
X4124Y99033D01*
X4173Y99094D01*
G03Y100974I-1172J940D01*
G01X4124Y101035D01*
X4000Y101361D01*
Y148707D01*
X4124Y149033D01*
X4173Y149094D01*
G03Y150974I-1172J940D01*
G01X4124Y151035D01*
X4000Y151361D01*
Y176990D01*
G02X5841Y177532I1000J1D01*
G03Y186420I6894J4444D01*
G02X4000Y186962I-841J541D01*
G01Y198707D01*
X4124Y199033D01*
X4173Y199094D01*
G03Y200974I-1172J940D01*
G01X4124Y201035D01*
X4000Y201361D01*
Y248707D01*
X4124Y249033D01*
X4173Y249094D01*
G03Y250974I-1172J940D01*
G01X4124Y251035D01*
X4000Y251361D01*
Y263825D01*
G02X5841Y264367I1000J1D01*
G03Y273255I6894J4444D01*
G02X4000Y273797I-841J541D01*
G01Y298707D01*
X4124Y299033D01*
X4173Y299094D01*
G03Y300974I-1172J940D01*
G01X4124Y301035D01*
X4000Y301361D01*
Y348707D01*
X4124Y349033D01*
X4173Y349094D01*
G03Y350974I-1172J940D01*
G01X4124Y351035D01*
X4000Y351361D01*
Y385848D01*
G02X5841Y386390I1000J1D01*
G03Y395278I6894J4444D01*
G02X4000Y395820I-841J541D01*
G01Y398707D01*
X4124Y399033D01*
X4173Y399094D01*
G03Y400974I-1172J940D01*
G01X4124Y401035D01*
X4000Y401361D01*
Y448707D01*
X4124Y449033D01*
X4173Y449094D01*
G03Y450974I-1172J940D01*
G01X4124Y451035D01*
X4000Y451361D01*
Y498707D01*
X4124Y499033D01*
X4173Y499094D01*
G03Y500974I-1172J940D01*
G01X4124Y501035D01*
X4000Y501361D01*
Y548707D01*
X4124Y549033D01*
X4173Y549094D01*
G03Y550974I-1172J940D01*
G01X4124Y551035D01*
X4000Y551361D01*
Y598707D01*
X4124Y599033D01*
X4173Y599094D01*
G03Y600974I-1172J940D01*
G01X4124Y601035D01*
X4000Y601361D01*
Y648707D01*
X4124Y649033D01*
X4173Y649094D01*
G03Y650974I-1172J940D01*
G01X4124Y651035D01*
X4000Y651361D01*
Y698707D01*
X4124Y699033D01*
X4173Y699094D01*
G03Y700974I-1172J940D01*
G01X4124Y701035D01*
X4000Y701361D01*
Y748707D01*
X4124Y749033D01*
X4173Y749094D01*
G03Y750974I-1172J940D01*
G01X4124Y751035D01*
X4000Y751361D01*
Y798707D01*
X4124Y799033D01*
X4173Y799094D01*
G03Y800974I-1172J940D01*
G01X4124Y801035D01*
X4000Y801361D01*
Y848707D01*
X4124Y849033D01*
X4173Y849094D01*
G03Y850974I-1172J940D01*
G01X4124Y851035D01*
X4000Y851361D01*
Y898707D01*
X4124Y899033D01*
X4173Y899094D01*
G03Y900974I-1172J940D01*
G01X4124Y901035D01*
X4000Y901361D01*
Y948707D01*
X4124Y949033D01*
X4173Y949094D01*
G03Y950974I-1172J940D01*
G01X4124Y951035D01*
X4000Y951361D01*
Y998707D01*
X4124Y999033D01*
X4173Y999094D01*
G03Y1000974I-1172J940D01*
G01X4124Y1001035D01*
X4000Y1001361D01*
Y1048707D01*
X4124Y1049033D01*
X4173Y1049094D01*
G03Y1050974I-1172J940D01*
G01X4124Y1051035D01*
X4000Y1051361D01*
Y1098707D01*
X4124Y1099033D01*
X4173Y1099094D01*
G03Y1100974I-1172J940D01*
G01X4124Y1101035D01*
X4000Y1101361D01*
Y1148707D01*
X4124Y1149033D01*
X4173Y1149094D01*
G03Y1150974I-1172J940D01*
G01X4124Y1151035D01*
X4000Y1151361D01*
Y1198707D01*
X4124Y1199033D01*
X4173Y1199094D01*
G03Y1200974I-1172J940D01*
G01X4124Y1201035D01*
X4000Y1201361D01*
Y1248707D01*
X4124Y1249033D01*
X4173Y1249094D01*
G03Y1250974I-1172J940D01*
G01X4124Y1251035D01*
X4000Y1251361D01*
Y1298707D01*
X4124Y1299033D01*
X4173Y1299094D01*
G03Y1300974I-1172J940D01*
G01X4124Y1301035D01*
X4000Y1301361D01*
Y1348707D01*
X4124Y1349033D01*
X4173Y1349094D01*
G03Y1350974I-1172J940D01*
G01X4124Y1351035D01*
X4000Y1351361D01*
Y1398707D01*
X4124Y1399033D01*
X4173Y1399094D01*
G03Y1400974I-1172J940D01*
G01X4124Y1401035D01*
X4000Y1401361D01*
Y1448707D01*
X4124Y1449033D01*
X4173Y1449094D01*
G03Y1450974I-1172J940D01*
G01X4124Y1451035D01*
X4000Y1451361D01*
Y1498707D01*
X4124Y1499033D01*
X4173Y1499094D01*
G03Y1500974I-1172J940D01*
G01X4124Y1501035D01*
X4000Y1501361D01*
Y1548707D01*
X4124Y1549033D01*
X4173Y1549094D01*
G03Y1550974I-1172J940D01*
G01X4124Y1551035D01*
X4000Y1551361D01*
Y1593269D01*
X4124Y1593595D01*
X4174Y1593657D01*
G03Y1595547I-1168J945D01*
G01X4124Y1595609D01*
X4000Y1595935D01*
Y1608826D01*
X4126Y1609154D01*
X4176Y1609217D01*
X4178Y1609219D01*
G03Y1611111I-1166J946D01*
G01X4176Y1611113D01*
X4126Y1611176D01*
X4000Y1611504D01*
Y1648707D01*
X4124Y1649033D01*
X4173Y1649094D01*
G03Y1650974I-1172J940D01*
G01X4124Y1651035D01*
X4000Y1651361D01*
Y1698707D01*
X4124Y1699033D01*
X4173Y1699094D01*
G03Y1700974I-1172J940D01*
G01X4124Y1701035D01*
X4000Y1701361D01*
Y1748707D01*
X4124Y1749033D01*
X4173Y1749094D01*
G03Y1750974I-1172J940D01*
G01X4124Y1751035D01*
X4000Y1751361D01*
Y1798707D01*
X4124Y1799033D01*
X4173Y1799094D01*
G03Y1800974I-1172J940D01*
G01X4124Y1801035D01*
X4000Y1801361D01*
Y1848707D01*
X4124Y1849033D01*
X4173Y1849094D01*
G03Y1850974I-1172J940D01*
G01X4124Y1851035D01*
X4000Y1851361D01*
Y1898707D01*
X4124Y1899033D01*
X4173Y1899094D01*
G03Y1900974I-1172J940D01*
G01X4124Y1901035D01*
X4000Y1901361D01*
Y1917305D01*
G02X5841Y1917847I1000J1D01*
G03Y1926735I6894J4444D01*
G02X4000Y1927277I-841J541D01*
G01Y1948707D01*
X4124Y1949033D01*
X4173Y1949094D01*
G03Y1950974I-1172J940D01*
G01X4124Y1951035D01*
X4000Y1951361D01*
Y1998707D01*
X4124Y1999033D01*
X4173Y1999094D01*
G03Y2000974I-1172J940D01*
G01X4124Y2001035D01*
X4000Y2001361D01*
Y2021675D01*
G02X5841Y2022217I1000J1D01*
G03Y2031105I6894J4444D01*
G02X4000Y2031647I-841J541D01*
G01Y2048707D01*
X4124Y2049033D01*
X4173Y2049094D01*
G03Y2050974I-1172J940D01*
G01X4124Y2051035D01*
X4000Y2051361D01*
Y2064961D01*
G02X5905Y2066866I1905J0D01*
G01X25507D01*
G02X25838Y2066741I0J-500D01*
G03X27828I995J1125D01*
G02X28159Y2066866I331J-375D01*
G01X75507D01*
G02X75838Y2066741I0J-500D01*
G03X77828I995J1125D01*
G02X78159Y2066866I331J-375D01*
G01X92520D01*
G03X102425Y2076772I0J9905D01*
G01Y2080709D01*
G02X104331Y2082614I1906J-1D01*
G01X108657D01*
X108984Y2082490D01*
X109046Y2082439D01*
G03X110936I945J1168D01*
G01X110998Y2082490D01*
X111325Y2082614D01*
X158657D01*
X158984Y2082490D01*
X159046Y2082439D01*
G03X160936I945J1168D01*
G01X160998Y2082490D01*
X161325Y2082614D01*
X208657D01*
X208984Y2082490D01*
X209046Y2082439D01*
G03X210936I945J1168D01*
G01X210998Y2082490D01*
X211325Y2082614D01*
X258657D01*
X258984Y2082490D01*
X259046Y2082439D01*
G03X260936I945J1168D01*
G01X260998Y2082490D01*
X261325Y2082614D01*
X308657D01*
X308984Y2082490D01*
X309046Y2082439D01*
G03X310936I945J1168D01*
G01X310998Y2082490D01*
X311325Y2082614D01*
X358657D01*
X358984Y2082490D01*
X359046Y2082439D01*
G03X360936I945J1168D01*
G01X360998Y2082490D01*
X361325Y2082614D01*
X397638D01*
G02X401512Y2078740I0J-3874D01*
G01Y2068434D01*
G02X401387Y2068103I-500J0D01*
G03Y2066113I1125J-995D01*
G02X401512Y2065782I-375J-331D01*
G01Y2018434D01*
G02X401387Y2018103I-500J0D01*
G03Y2016113I1125J-995D01*
G02X401512Y2015782I-375J-331D01*
G01Y1968434D01*
G02X401387Y1968103I-500J0D01*
G03Y1966113I1125J-995D01*
G02X401512Y1965782I-375J-331D01*
G01Y1918434D01*
G02X401387Y1918103I-500J0D01*
G03Y1916113I1125J-995D01*
G02X401512Y1915782I-375J-331D01*
G01Y1868434D01*
G02X401387Y1868103I-500J0D01*
G03Y1866113I1125J-995D01*
G02X401512Y1865782I-375J-331D01*
G01Y1818434D01*
G02X401387Y1818103I-500J0D01*
G03Y1816113I1125J-995D01*
G02X401512Y1815782I-375J-331D01*
G01Y1768434D01*
G02X401387Y1768103I-500J0D01*
G03Y1766113I1125J-995D01*
G02X401512Y1765782I-375J-331D01*
G01Y1718434D01*
G02X401387Y1718103I-500J0D01*
G03Y1716113I1125J-995D01*
G02X401512Y1715782I-375J-331D01*
G01Y1668434D01*
G02X401387Y1668103I-500J0D01*
G03Y1666113I1125J-995D01*
G02X401512Y1665782I-375J-331D01*
G01Y1618434D01*
G02X401387Y1618103I-500J0D01*
G03Y1616113I1125J-995D01*
G02X401512Y1615782I-375J-331D01*
G01Y1568434D01*
G02X401387Y1568103I-500J0D01*
G03Y1566113I1125J-995D01*
G02X401512Y1565782I-375J-331D01*
G01Y1518434D01*
G02X401387Y1518103I-500J0D01*
G03Y1516113I1125J-995D01*
G02X401512Y1515782I-375J-331D01*
G01Y1468434D01*
G02X401387Y1468103I-500J0D01*
G03Y1466113I1125J-995D01*
G02X401512Y1465782I-375J-331D01*
G01Y1418434D01*
G02X401387Y1418103I-500J0D01*
G03Y1416113I1125J-995D01*
G02X401512Y1415782I-375J-331D01*
G01Y1368434D01*
G02X401387Y1368103I-500J0D01*
G03Y1366113I1125J-995D01*
G02X401512Y1365782I-375J-331D01*
G01Y1318434D01*
G02X401387Y1318103I-500J0D01*
G03Y1316113I1125J-995D01*
G02X401512Y1315782I-375J-331D01*
G01Y1268434D01*
G02X401387Y1268103I-500J0D01*
G03Y1266113I1125J-995D01*
G02X401512Y1265782I-375J-331D01*
G01Y1218434D01*
G02X401387Y1218103I-500J0D01*
G03Y1216113I1125J-995D01*
G02X401512Y1215782I-375J-331D01*
G01Y1168434D01*
G02X401387Y1168103I-500J0D01*
G03Y1166113I1125J-995D01*
G02X401512Y1165782I-375J-331D01*
G01Y1118434D01*
G02X401387Y1118103I-500J0D01*
G03Y1116113I1125J-995D01*
G02X401512Y1115782I-375J-331D01*
G01Y1068434D01*
G02X401387Y1068103I-500J0D01*
G03Y1066113I1125J-995D01*
G02X401512Y1065782I-375J-331D01*
G01Y1018434D01*
G02X401387Y1018103I-500J0D01*
G03Y1016113I1125J-995D01*
G02X401512Y1015782I-375J-331D01*
G01Y968434D01*
G02X401387Y968103I-500J0D01*
G03Y966113I1125J-995D01*
G02X401512Y965782I-375J-331D01*
G01Y918434D01*
G02X401387Y918103I-500J0D01*
G03Y916113I1125J-995D01*
G02X401512Y915782I-375J-331D01*
G01Y868434D01*
G02X401387Y868103I-500J0D01*
G03Y866113I1125J-995D01*
G02X401512Y865782I-375J-331D01*
G01Y818434D01*
G02X401387Y818103I-500J0D01*
G03Y816113I1125J-995D01*
G02X401512Y815782I-375J-331D01*
G01Y768434D01*
G02X401387Y768103I-500J0D01*
G03Y766113I1125J-995D01*
G02X401512Y765782I-375J-331D01*
G01Y718434D01*
G02X401387Y718103I-500J0D01*
G03Y716113I1125J-995D01*
G02X401512Y715782I-375J-331D01*
G01Y668434D01*
G02X401387Y668103I-500J0D01*
G03Y666113I1125J-995D01*
G02X401512Y665782I-375J-331D01*
G01Y618434D01*
G02X401387Y618103I-500J0D01*
G03Y616113I1125J-995D01*
G02X401512Y615782I-375J-331D01*
G01Y568434D01*
G02X401387Y568103I-500J0D01*
G03Y566113I1125J-995D01*
G02X401512Y565782I-375J-331D01*
G01Y518434D01*
G02X401387Y518103I-500J0D01*
G03Y516113I1125J-995D01*
G02X401512Y515782I-375J-331D01*
G01Y468434D01*
G02X401387Y468103I-500J0D01*
G03Y466113I1125J-995D01*
G02X401512Y465782I-375J-331D01*
G01Y418434D01*
G02X401387Y418103I-500J0D01*
G03Y416113I1125J-995D01*
G02X401512Y415782I-375J-331D01*
G01Y368434D01*
G02X401387Y368103I-500J0D01*
G03Y366113I1125J-995D01*
G02X401512Y365782I-375J-331D01*
G01Y318434D01*
G02X401387Y318103I-500J0D01*
G03Y316113I1125J-995D01*
G02X401512Y315782I-375J-331D01*
G01Y268434D01*
G02X401387Y268103I-500J0D01*
G03Y266113I1125J-995D01*
G02X401512Y265782I-375J-331D01*
G01Y218434D01*
G02X401387Y218103I-500J0D01*
G03Y216113I1125J-995D01*
G02X401512Y215782I-375J-331D01*
G01Y168434D01*
G02X401387Y168103I-500J0D01*
G03Y166113I1125J-995D01*
G02X401512Y165782I-375J-331D01*
G01Y118434D01*
G02X401387Y118103I-500J0D01*
G03Y116113I1125J-995D01*
G02X401512Y115782I-375J-331D01*
G01Y68434D01*
G02X401387Y68103I-500J0D01*
G03Y66113I1125J-995D01*
G02X401512Y65782I-375J-331D01*
G01Y18434D01*
G02X401387Y18103I-500J0D01*
G03Y16113I1125J-995D01*
G02X401512Y15782I-375J-331D01*
G01Y7874D01*
G02X397638Y4000I-3874J0D01*
G01X376547D01*
X376220Y4124D01*
X376159Y4173D01*
G03X374279I-940J-1171D01*
G01X374218Y4124D01*
X373891Y4000D01*
X326547D01*
X326220Y4124D01*
X326159Y4173D01*
G03X324279I-940J-1171D01*
G01X324218Y4124D01*
X323891Y4000D01*
X276547D01*
X276220Y4124D01*
X276159Y4173D01*
G03X274279I-940J-1171D01*
G01X274218Y4124D01*
X273891Y4000D01*
X226547D01*
X226220Y4124D01*
X226159Y4173D01*
G03X224279I-940J-1171D01*
G01X224218Y4124D01*
X223891Y4000D01*
X176547D01*
X176220Y4124D01*
X176159Y4173D01*
G03X174279I-940J-1171D01*
G01X174218Y4124D01*
X173891Y4000D01*
X126547D01*
X126220Y4124D01*
X126159Y4173D01*
G03X124279I-940J-1171D01*
G01X124218Y4124D01*
X123891Y4000D01*
X104331D01*
G37*
%LPD*%
G75*
G36*
G01X86043Y1864960D02*
G02X74584Y1846445I-20688J0D01*
G02X75698Y1882876I-9230J18515D01*
G02X86043Y1864960I-10343J-17917D01*
G37*
G36*
G01X292850Y1881102D02*
Y1885039D01*
G02X321322I14236J0D01*
G01Y1881102D01*
G02X292850I-14236J0D01*
G37*
G36*
G01X17976Y989245D02*
Y990190D01*
G02X22970Y990185I2491J-5857D01*
G01Y989240D01*
G03X23209Y988813I500J0D01*
G02X23856Y988346I-2741J-4480D01*
G01X25407D01*
G02X14103Y984333I-4940J-4013D01*
G02X15503Y988316I6365J0D01*
G01X17045D01*
G02X17736Y988818I3422J-3984D01*
G03X17976Y989245I-260J427D01*
G37*
G36*
G01X17980Y1347510D02*
Y1348455D01*
G02X22974Y1348450I2491J-5857D01*
G01Y1347505D01*
G03X23213Y1347078I500J0D01*
G02X23859Y1346612I-2741J-4480D01*
G01X25411D01*
G02X14107Y1342598I-4939J-4014D01*
G02X15507Y1346580I6365J-1D01*
G01X17048D01*
G02X17740Y1347083I3424J-3982D01*
G03X17980Y1347510I-260J427D01*
G37*
G54D42*
X65354Y114960D03*
G54D40*
X307087Y2043503D03*
Y1693503D03*
Y1343503D03*
Y827164D03*
X307088Y477164D03*
X307086Y127164D03*
G54D49*
Y308267D03*
G54D48*
X163385Y27205D03*
Y202205D03*
Y377205D03*
X163386Y552205D03*
Y727205D03*
X163385Y902205D03*
Y1077205D03*
Y1252205D03*
Y1427205D03*
Y1602205D03*
Y1777205D03*
Y1952205D03*
G54D45*
X57735Y2026661D03*
Y1922291D03*
Y390834D03*
Y268811D03*
Y181976D03*
Y59953D03*
G54D47*
X20472Y1054606D03*
G54D43*
X373385Y1957520D03*
Y1782520D03*
Y1607520D03*
Y1432520D03*
Y1257520D03*
Y1082520D03*
Y907520D03*
X373386Y732520D03*
Y557520D03*
X373385Y382520D03*
Y207520D03*
Y32520D03*
G54D46*
X58995Y1587992D03*
Y543701D03*
X13995Y1587992D03*
Y543701D03*
G54D44*
X359842Y2003780D03*
Y1828779D03*
Y1653780D03*
Y1478780D03*
Y1303780D03*
Y1128779D03*
Y953780D03*
Y778780D03*
Y603779D03*
Y428779D03*
Y253780D03*
Y78780D03*
G54D41*
X65354Y1514960D03*
Y1164960D03*
Y814960D03*
Y464960D03*
G54D11*
X25219Y18752D03*
X3001Y52034D03*
Y100034D03*
Y150034D03*
Y200034D03*
Y250034D03*
Y300034D03*
Y350034D03*
Y400034D03*
Y450034D03*
Y500034D03*
Y550034D03*
X11677Y578766D03*
X3001Y600034D03*
Y650034D03*
Y700034D03*
Y750034D03*
Y800034D03*
Y850034D03*
Y900034D03*
Y950034D03*
Y1000034D03*
Y1050034D03*
Y1100034D03*
Y1150034D03*
Y1200034D03*
Y1250034D03*
Y1300034D03*
Y1350034D03*
Y1400034D03*
Y1450034D03*
Y1500034D03*
Y1550034D03*
X16484Y1552159D03*
X11085Y1552589D03*
X3006Y1594602D03*
X3012Y1610165D03*
X3001Y1650034D03*
Y1700034D03*
Y1750034D03*
Y1800034D03*
Y1850034D03*
Y1900034D03*
Y1950034D03*
Y2000034D03*
Y2050034D03*
X48433Y866179D03*
X48467Y869278D03*
X49441Y1238962D03*
X46980Y1335843D03*
Y1325843D03*
Y1315843D03*
Y1320843D03*
Y1330843D03*
Y1345843D03*
Y1340843D03*
X26833Y2067866D03*
X58750Y579653D03*
X63820Y579654D03*
X61888Y666012D03*
X57124Y675327D03*
X54483Y679810D03*
X59236Y670758D03*
X70865Y854278D03*
Y872278D03*
Y866278D03*
Y860278D03*
Y897750D03*
Y890116D03*
X60815Y1019026D03*
X63577Y1019115D03*
X57458Y1253378D03*
X54543Y1296513D03*
X63061Y1296312D03*
X67568Y1296654D03*
X61866Y1309190D03*
X67568Y1307829D03*
X54543Y1308995D03*
X61866Y1342104D03*
X54108Y1559138D03*
X75219Y18752D03*
X97417Y32853D03*
Y37438D03*
X97536Y376580D03*
X97457Y371909D03*
X97985Y391220D03*
X97643Y396024D03*
X93223Y417736D03*
X94347Y421562D03*
X98591Y720745D03*
X98564Y715937D03*
X97443Y739962D03*
X97534Y735248D03*
X98124Y745139D03*
X95775Y751469D03*
X92216Y899865D03*
X90708Y878615D03*
X92633Y907404D03*
X92989Y927334D03*
X98139Y990959D03*
X76446Y1014871D03*
X79499D03*
X96904Y1067515D03*
X82763Y1060051D03*
X96948Y1092036D03*
X96949Y1087095D03*
X96774Y1072226D03*
X96684Y1081791D03*
X75475Y1315303D03*
X96510Y1395382D03*
X97403Y1424340D03*
X97825Y1419492D03*
X96993Y1443743D03*
X96996Y1438980D03*
X97465Y1447919D03*
X95236Y1453321D03*
X76833Y2067866D03*
X106335Y22580D03*
X106958Y26285D03*
X108082Y38899D03*
X102646Y49461D03*
X101430Y41803D03*
X107405Y49898D03*
X107037Y34687D03*
X104350Y62293D03*
X107263Y72244D03*
X109054Y58250D03*
X104116Y82557D03*
X107213Y85169D03*
X106836Y376461D03*
X106709Y391219D03*
X105451Y406795D03*
X114498Y396207D03*
X101990Y426104D03*
X109475Y434743D03*
X111017Y419566D03*
X107025Y725368D03*
X105087Y754126D03*
X106935Y745139D03*
X107173Y735219D03*
X101244Y774100D03*
X112836Y769122D03*
X113697Y794293D03*
X105395Y972040D03*
X102611Y972220D03*
X100687Y999391D03*
X107351Y1093484D03*
X107235Y1081791D03*
X107215Y1072208D03*
X98652Y1096403D03*
X108779Y1105760D03*
X105152Y1118381D03*
X112503Y1115860D03*
X105684Y1125919D03*
X108468Y1129286D03*
X100719Y1312810D03*
Y1306810D03*
Y1330810D03*
Y1336810D03*
Y1324810D03*
Y1318810D03*
Y1346065D03*
X101626Y1397635D03*
X106962Y1434041D03*
X106921Y1419492D03*
X106763Y1444599D03*
X107006Y1452651D03*
X105455Y1472894D03*
X108574Y1463389D03*
X113518Y1489571D03*
X99103Y1765722D03*
X99068Y1760827D03*
X107355Y1770437D03*
X99047Y1785571D03*
X98873Y1780542D03*
X99294Y1789947D03*
X107391Y1794460D03*
X107220Y1791589D03*
X107373Y1780544D03*
X105669Y1815227D03*
X108819Y1812118D03*
X106819Y1802230D03*
X108819Y1824470D03*
X109991Y2083607D03*
X125219Y3002D03*
X144878Y1738861D03*
X162384Y56744D03*
X157558Y51426D03*
X161742Y72497D03*
X162586Y68130D03*
X159417Y91281D03*
X158901Y85017D03*
X161377Y407575D03*
X156865Y401207D03*
X161257Y420869D03*
X159019Y439268D03*
X158807Y432969D03*
X156610Y751063D03*
X161826Y756757D03*
X161131Y774878D03*
X161644Y764231D03*
X158956Y780982D03*
X159053Y787280D03*
X164539Y1116135D03*
X162140Y1106853D03*
X156854Y1101031D03*
X159382Y1136151D03*
X158456Y1129045D03*
X158618Y1399448D03*
X164037Y1400226D03*
X170351Y1401324D03*
X159192Y1451105D03*
X163099Y1457084D03*
X162524Y1462651D03*
X162242Y1471380D03*
X159216Y1477124D03*
X159526Y1483434D03*
X150309Y1737009D03*
X168151Y1739208D03*
X156183Y1735240D03*
X165782Y1732903D03*
X163257Y1737619D03*
X163250Y1815631D03*
X162140Y1807740D03*
X156452Y1800821D03*
X159822Y1831380D03*
X159075Y1825087D03*
X159991Y2083607D03*
X175219Y3002D03*
X184284Y948331D03*
X175989Y944537D03*
X176011Y936829D03*
X184196Y967371D03*
X175359Y963486D03*
X175561Y955964D03*
X175135Y972490D03*
X184632Y983423D03*
X175022Y980281D03*
X175742Y989958D03*
X175449Y997660D03*
X184353Y1001556D03*
X184118Y1019280D03*
X188385Y1020810D03*
X175698Y1008730D03*
X175473Y1016296D03*
X175448Y1031766D03*
X175897Y1023997D03*
X176083Y1402321D03*
X173394Y1736051D03*
X209991Y2083607D03*
X225219Y3002D03*
X267627Y115559D03*
X256947Y128276D03*
X257125Y115559D03*
X265722Y463102D03*
X265737Y473680D03*
X255837Y823626D03*
X255687Y812192D03*
X259991Y2083607D03*
X275219Y3002D03*
X287420Y162540D03*
X283086Y162675D03*
X271547Y245353D03*
X276617Y241400D03*
X281193Y241624D03*
X285513Y337688D03*
X281074D03*
X289895D03*
X286665Y417844D03*
X291002D03*
X281569Y421169D03*
X274991Y463099D03*
X282776Y512341D03*
X278405D03*
X273938D03*
X269516D03*
X285348Y595540D03*
X290984Y592215D03*
X274514Y687192D03*
X270109D03*
X283340D03*
X278955D03*
X273114Y770968D03*
X278184Y767643D03*
X282737D03*
X270070Y812192D03*
X276686Y862488D03*
X272181Y862354D03*
X285788Y862237D03*
X281305D03*
X275966Y944767D03*
X281194Y941442D03*
X285874D03*
X285666Y1031162D03*
X281124D03*
X290107D03*
X282958Y1119471D03*
X288188Y1116146D03*
X289082Y1206777D03*
X284194D03*
X279559D03*
X283808Y1293959D03*
X289210Y1290634D03*
X284240Y1389544D03*
X279518Y1389543D03*
X275052Y1389715D03*
X270579Y1389626D03*
X270234Y1467760D03*
X275521Y1464435D03*
X279990D03*
X289675Y1558211D03*
X285054D03*
X284086Y1644883D03*
X289421Y1641558D03*
X274704Y1738196D03*
X279703Y1738398D03*
X284583Y1738465D03*
X289499Y1738735D03*
X281066Y1819569D03*
X291550Y1814846D03*
X286623Y1814400D03*
X280240Y1858668D03*
X279976Y1864565D03*
X287121Y1913327D03*
X282717D03*
X278262D03*
X273817D03*
X299687Y63778D03*
X304151D03*
X308651D03*
X313089D03*
X294483Y67732D03*
X296523Y162585D03*
X291943Y162630D03*
X308057Y248863D03*
X306267Y241010D03*
X314914Y238162D03*
X314940Y252083D03*
X305867Y258589D03*
X294506Y337688D03*
X295509Y592215D03*
X294617Y1031162D03*
X309678Y1053262D03*
X292698Y1116146D03*
X312527Y1162266D03*
X312698Y1172804D03*
X293807Y1206777D03*
X294133Y1290634D03*
X314183Y1403423D03*
X313894Y1513883D03*
X302267Y1524401D03*
X301734Y1513883D03*
X312077Y1575871D03*
X298870Y1558211D03*
X294392D03*
X294090Y1641558D03*
X311539Y1753499D03*
X293606Y1858668D03*
X314562Y1994087D03*
X309991Y2083607D03*
X325219Y3002D03*
X331403Y51409D03*
X333889Y56021D03*
X338227Y61559D03*
X322005Y63778D03*
X317567D03*
X320372Y225979D03*
X318088Y231820D03*
X321899Y238137D03*
X329930Y245684D03*
X331046Y232021D03*
X320961Y250105D03*
X324709Y231580D03*
X335522Y404033D03*
X323313Y418313D03*
X326196Y413982D03*
X328950Y409216D03*
X320980Y423225D03*
X336617Y577978D03*
X319305Y582111D03*
X329636Y584715D03*
X317724Y588250D03*
X337387Y586230D03*
X320380Y576491D03*
X331867Y589810D03*
X333750Y595326D03*
X323751Y589155D03*
X319852Y593330D03*
X321742Y599041D03*
X331568Y752967D03*
X339012Y752859D03*
X329336Y762693D03*
X334010Y758588D03*
X327524Y758020D03*
X339615Y926357D03*
X329938Y948756D03*
X332527Y943746D03*
X324098Y946104D03*
X318557Y941178D03*
X323868Y929978D03*
X326646Y939788D03*
X333300Y928464D03*
X336160Y937262D03*
X328583Y933262D03*
X321425Y951577D03*
X324246Y1051786D03*
X335677Y1048904D03*
X317592Y1053050D03*
X331920Y1116088D03*
X337509Y1109598D03*
X328989Y1121090D03*
X326558Y1126368D03*
X325796Y1162266D03*
X327452Y1279447D03*
X321978Y1282086D03*
X338047Y1282599D03*
X333242Y1276809D03*
X329619Y1284016D03*
X327932Y1289221D03*
X319404Y1401346D03*
X325636Y1399114D03*
X334646Y1400804D03*
X323720Y1570924D03*
X329399Y1571939D03*
X317243Y1574832D03*
X333474Y1566686D03*
X335963Y1573797D03*
X329887Y1752081D03*
X321283Y1753466D03*
X335730Y1753270D03*
X338309Y1927623D03*
X332399Y1926787D03*
X324803Y1990272D03*
X320045Y1990215D03*
X359931Y52189D03*
X348289Y50863D03*
X345089Y56190D03*
X340373Y51579D03*
X342097Y401684D03*
X363825Y401768D03*
X342900Y580126D03*
X362577Y752783D03*
X344109Y751809D03*
X343656Y933725D03*
X345578Y1047844D03*
X344099Y1106798D03*
X349855Y1104302D03*
X344130Y1401670D03*
X350690Y1403243D03*
X348710Y1570187D03*
X361011Y1568890D03*
X343402Y1572080D03*
X348245Y1575241D03*
X355364Y1570990D03*
X345537Y1916558D03*
X344402Y1911123D03*
X363361Y1918313D03*
X358318Y1920680D03*
X363411Y1923459D03*
X340336Y1922409D03*
X347676Y1922165D03*
X359991Y2083607D03*
X375219Y3002D03*
X372204Y56126D03*
X365720Y52336D03*
X379257Y52158D03*
X379572Y58441D03*
X387524Y76847D03*
X374442Y406857D03*
X380619Y410112D03*
X380878Y403999D03*
X374542Y401282D03*
X368907Y404308D03*
X376654Y754748D03*
X382892Y767710D03*
X386790Y774338D03*
X380186Y761742D03*
X379335Y1189778D03*
X383276Y1184136D03*
X386816Y1179841D03*
X376472Y1194999D03*
X373674Y1199967D03*
X371523Y1204725D03*
X367829Y1566108D03*
X374775Y1919243D03*
X379403Y1917261D03*
X369748Y1921795D03*
X402512Y17108D03*
Y67108D03*
Y117108D03*
Y167108D03*
Y217108D03*
Y267108D03*
Y317108D03*
Y367108D03*
Y417108D03*
Y467108D03*
Y517108D03*
Y567108D03*
Y617108D03*
Y667108D03*
Y717108D03*
Y767108D03*
X391278Y765894D03*
X402512Y817108D03*
Y867108D03*
Y917108D03*
Y967108D03*
Y1017108D03*
Y1067108D03*
Y1117108D03*
Y1167108D03*
Y1217108D03*
Y1267108D03*
Y1317108D03*
Y1367108D03*
Y1417108D03*
Y1467108D03*
Y1517108D03*
Y1567108D03*
Y1617108D03*
Y1667108D03*
Y1717108D03*
Y1767108D03*
Y1817108D03*
Y1867108D03*
Y1917108D03*
Y1967108D03*
Y2017108D03*
Y2067108D03*
G54D28*
X166500Y126110D03*
Y118626D03*
Y111407D03*
X166329Y140623D03*
X166500Y132705D03*
X166329Y148066D03*
Y156102D03*
Y163621D03*
X156430Y461714D03*
Y483012D03*
X156259Y490930D03*
X156430Y468933D03*
Y476417D03*
X156259Y513928D03*
Y498373D03*
Y506409D03*
X155444Y822725D03*
X162872D03*
Y830209D03*
X155444D03*
X171524Y844722D03*
Y852165D03*
X162872Y836804D03*
X155444D03*
X162701Y844722D03*
X155273D03*
X162701Y852165D03*
X155273D03*
X171524Y860201D03*
Y867720D03*
X162701Y860201D03*
X155273D03*
X162701Y867720D03*
X155273D03*
X169375Y1176256D03*
Y1190335D03*
Y1183740D03*
X153124Y1176256D03*
X160552D03*
Y1183740D03*
Y1190335D03*
X153124D03*
Y1183740D03*
X160552Y1169037D03*
X153124D03*
X169204Y1198253D03*
X160381D03*
X152953D03*
X154109Y1499221D03*
X161537D03*
Y1506440D03*
X170360D03*
X154109D03*
X153938Y1528437D03*
X154109Y1513924D03*
Y1520519D03*
X170360Y1513924D03*
Y1520519D03*
X161537D03*
Y1513924D03*
X161366Y1528437D03*
X170189D03*
X153938Y1535880D03*
Y1543916D03*
Y1551435D03*
X170189Y1535880D03*
Y1543916D03*
X161366Y1535880D03*
Y1543916D03*
Y1551435D03*
X170189D03*
X152091Y1866003D03*
X159519D03*
X152091Y1880706D03*
Y1887301D03*
X168342Y1880706D03*
Y1887301D03*
X159519D03*
Y1880706D03*
Y1873222D03*
X168342D03*
X152091D03*
X151920Y1902662D03*
Y1910698D03*
X168171Y1902662D03*
Y1910698D03*
X159348Y1902662D03*
Y1910698D03*
X151920Y1895219D03*
X159348D03*
X168171D03*
X151920Y1918217D03*
X159348D03*
X168171D03*
X173928Y126110D03*
Y118626D03*
Y111407D03*
X173757Y140623D03*
X173928Y132705D03*
X173757Y148066D03*
Y156102D03*
Y163621D03*
X175033Y261594D03*
Y268813D03*
Y282892D03*
X174862Y290810D03*
Y298253D03*
X175033Y276297D03*
X174862Y313808D03*
Y306289D03*
X179191Y822725D03*
Y830209D03*
X171695Y822725D03*
Y830209D03*
X179191Y836804D03*
X171695D03*
X179020Y844722D03*
Y852165D03*
Y860201D03*
Y867720D03*
X176871Y1176256D03*
Y1190335D03*
Y1183740D03*
X176700Y1198253D03*
X177856Y1506440D03*
Y1513924D03*
Y1520519D03*
X177685Y1528437D03*
Y1535880D03*
Y1543916D03*
Y1551435D03*
X175838Y1880706D03*
Y1887301D03*
Y1873222D03*
X175667Y1902662D03*
Y1910698D03*
Y1895219D03*
Y1918217D03*
X240955Y56999D03*
Y64483D03*
X240784Y78996D03*
X240955Y71078D03*
X240784Y94475D03*
Y101994D03*
Y86439D03*
X236537Y244995D03*
X227714Y237776D03*
Y244995D03*
X244033D03*
X236537Y259074D03*
X236366Y266992D03*
Y274435D03*
X227714Y259074D03*
X227543Y266992D03*
Y274435D03*
X244033Y259074D03*
X243862Y266992D03*
Y274435D03*
X236537Y252479D03*
X227714D03*
X244033D03*
X236366Y289990D03*
X227543D03*
X243862D03*
X236366Y282471D03*
X227543D03*
X243862D03*
X232548Y461083D03*
X241371Y482381D03*
X241200Y490299D03*
X232548Y482381D03*
X232377Y490299D03*
X241371Y468302D03*
Y475786D03*
X232548Y468302D03*
Y475786D03*
X241200Y513297D03*
X232377D03*
X241200Y497742D03*
X232377D03*
X241200Y505778D03*
X232377D03*
X230963Y608108D03*
X238391D03*
X230963Y601513D03*
X238391D03*
Y594029D03*
X230963D03*
X230792Y631505D03*
X238220D03*
X230792Y623469D03*
X238220D03*
X230792Y616026D03*
X238220D03*
X230792Y639024D03*
X238220D03*
X231339Y959673D03*
X238767D03*
Y967157D03*
Y973752D03*
X231339D03*
Y967157D03*
X238767Y952454D03*
X231339D03*
X238596Y981670D03*
X231168D03*
X238596Y997149D03*
Y989113D03*
X231168Y997149D03*
Y989113D03*
X238596Y1004668D03*
X231168D03*
X238659Y1215296D03*
X231231D03*
X238659Y1207777D03*
Y1199741D03*
X231231Y1207777D03*
Y1199741D03*
X225131Y1663167D03*
X241382Y1670386D03*
X232559Y1663167D03*
Y1670386D03*
X225131D03*
X241211Y1699826D03*
X241382Y1677870D03*
X241211Y1692383D03*
X241382Y1684465D03*
X232559D03*
Y1677870D03*
X232388Y1692383D03*
Y1699826D03*
X225131Y1684465D03*
Y1677870D03*
X224960Y1692383D03*
Y1699826D03*
X241211Y1715381D03*
Y1707862D03*
X232388D03*
Y1715381D03*
X224960Y1707862D03*
Y1715381D03*
X248451Y56999D03*
Y64483D03*
X248280Y78996D03*
X248451Y71078D03*
X248280Y94475D03*
Y101994D03*
Y86439D03*
X248867Y482381D03*
X248696Y490299D03*
X248867Y468302D03*
Y475786D03*
X248696Y513297D03*
Y497742D03*
Y505778D03*
X254710Y608108D03*
Y601513D03*
Y594029D03*
X247214Y608108D03*
Y601513D03*
Y594029D03*
X254539Y631505D03*
Y623469D03*
Y616026D03*
X247043Y631505D03*
Y623469D03*
Y616026D03*
X267433Y624321D03*
X254539Y639024D03*
X247043D03*
X255086Y959673D03*
Y973752D03*
Y967157D03*
X247590Y959673D03*
Y973752D03*
Y967157D03*
X254915Y981670D03*
Y997149D03*
Y989113D03*
X247419Y981670D03*
Y997149D03*
Y989113D03*
X254915Y1004668D03*
X247419D03*
X254978Y1215296D03*
X247482D03*
X254978Y1207777D03*
Y1199741D03*
X247482Y1207777D03*
Y1199741D03*
X248878Y1670386D03*
X248707Y1699826D03*
X248878Y1677870D03*
Y1684465D03*
X248707Y1692383D03*
Y1707862D03*
Y1715381D03*
X279044Y624627D03*
X354391Y1329686D03*
Y1350706D03*
Y1360043D03*
Y1340201D03*
Y1376210D03*
Y1367771D03*
X366169Y1329686D03*
Y1350706D03*
Y1360043D03*
Y1340201D03*
Y1376210D03*
Y1367771D03*
G54D31*
X173385Y32520D03*
Y21890D03*
X183385Y32520D03*
Y21890D03*
X193385Y32520D03*
Y21890D03*
X173385Y196890D03*
X183385D03*
X193385D03*
X173385Y207520D03*
X183385D03*
X193385D03*
X173385Y371890D03*
X183385D03*
X193385D03*
X173385Y382520D03*
X183385D03*
X193385D03*
X173386Y557520D03*
Y546890D03*
X183386Y557520D03*
Y546890D03*
X193386Y557520D03*
Y546890D03*
X173386Y732520D03*
Y721890D03*
X183386Y732520D03*
Y721890D03*
X193386Y732520D03*
Y721890D03*
X173385Y896890D03*
X183385D03*
X193385D03*
X173385Y907520D03*
X183385D03*
X193385D03*
X173385Y1071890D03*
X183385D03*
X193385D03*
X173385Y1082520D03*
X183385D03*
X193385D03*
X173385Y1257520D03*
Y1246890D03*
X183385Y1257520D03*
Y1246890D03*
X193385Y1257520D03*
Y1246890D03*
X173385Y1432520D03*
Y1421890D03*
X183385Y1432520D03*
Y1421890D03*
X193385Y1432520D03*
Y1421890D03*
X173385Y1596890D03*
X183385D03*
X193385D03*
X173385Y1607520D03*
X183385D03*
X193385D03*
X173385Y1771890D03*
X183385D03*
X193385D03*
X173385Y1782520D03*
X183385D03*
X193385D03*
X173385Y1957520D03*
Y1946890D03*
X183385Y1957520D03*
Y1946890D03*
X193385Y1957520D03*
Y1946890D03*
X203385Y32520D03*
Y21890D03*
X213385Y32520D03*
Y21890D03*
X203385Y196890D03*
X213385D03*
X203385Y207520D03*
X213385D03*
X203385Y371890D03*
X213385D03*
X203385Y382520D03*
X213385D03*
X203386Y557520D03*
Y546890D03*
X213386Y557520D03*
Y546890D03*
X203386Y732520D03*
Y721890D03*
X213386Y732520D03*
Y721890D03*
X203385Y896890D03*
X213385D03*
X203385Y907520D03*
X213385D03*
X203385Y1071890D03*
X213385D03*
X203385Y1082520D03*
X213385D03*
X203385Y1257520D03*
Y1246890D03*
X213385Y1257520D03*
Y1246890D03*
X203385Y1432520D03*
Y1421890D03*
X213385Y1432520D03*
Y1421890D03*
X203385Y1596890D03*
X213385D03*
X203385Y1607520D03*
X213385D03*
X203385Y1771890D03*
X213385D03*
X203385Y1782520D03*
X213385D03*
X203385Y1957520D03*
Y1946890D03*
X213385Y1957520D03*
Y1946890D03*
X223385Y32520D03*
Y21890D03*
X233385Y32520D03*
Y21890D03*
X243385Y32520D03*
Y21890D03*
X223385Y196890D03*
X233385D03*
X243385D03*
X223385Y207520D03*
X233385D03*
X243385D03*
X223385Y371890D03*
X233385D03*
X243385D03*
X223385Y382520D03*
X233385D03*
X243385D03*
X223386Y557520D03*
Y546890D03*
X233386Y557520D03*
Y546890D03*
X243386Y557520D03*
Y546890D03*
X223386Y732520D03*
Y721890D03*
X233386Y732520D03*
Y721890D03*
X243386Y732520D03*
Y721890D03*
X223385Y896890D03*
X233385D03*
X243385D03*
X223385Y907520D03*
X233385D03*
X243385D03*
X223385Y1071890D03*
X233385D03*
X243385D03*
X223385Y1082520D03*
X233385D03*
X243385D03*
X223385Y1257520D03*
Y1246890D03*
X233385Y1257520D03*
Y1246890D03*
X243385Y1257520D03*
Y1246890D03*
X223385Y1432520D03*
Y1421890D03*
X233385Y1432520D03*
Y1421890D03*
X243385Y1432520D03*
Y1421890D03*
X223385Y1596890D03*
X233385D03*
X243385D03*
X223385Y1607520D03*
X233385D03*
X243385D03*
X223385Y1771890D03*
X233385D03*
X243385D03*
X223385Y1782520D03*
X233385D03*
X243385D03*
X223385Y1957520D03*
Y1946890D03*
X233385Y1957520D03*
Y1946890D03*
X243385Y1957520D03*
Y1946890D03*
X337165Y24705D03*
Y34705D03*
Y199705D03*
Y209705D03*
Y374705D03*
Y384705D03*
X337166Y549705D03*
Y559705D03*
Y724705D03*
Y734705D03*
X337165Y899705D03*
Y909705D03*
Y1074705D03*
Y1084705D03*
Y1249705D03*
Y1259705D03*
Y1424705D03*
Y1434705D03*
Y1599705D03*
Y1609705D03*
Y1774705D03*
Y1784705D03*
Y1949705D03*
Y1959705D03*
X342165Y19705D03*
Y29705D03*
X347165Y24705D03*
X352165Y19705D03*
Y29705D03*
X357165Y24705D03*
X362165Y19705D03*
Y29705D03*
X347165Y34705D03*
X357165D03*
X342165Y194705D03*
X347165Y199705D03*
X352165Y194705D03*
X357165Y199705D03*
X362165Y194705D03*
X342165Y204705D03*
X347165Y209705D03*
X352165Y204705D03*
X357165Y209705D03*
X362165Y204705D03*
X342165Y369705D03*
X352165D03*
X362165D03*
X342165Y379705D03*
X347165Y374705D03*
Y384705D03*
X352165Y379705D03*
X357165Y374705D03*
Y384705D03*
X362165Y379705D03*
X342166Y544705D03*
Y554705D03*
X347166Y549705D03*
Y559705D03*
X352166Y544705D03*
Y554705D03*
X357166Y549705D03*
Y559705D03*
X362166Y544705D03*
Y554705D03*
X342166Y719705D03*
Y729705D03*
X347166Y724705D03*
X352166Y719705D03*
Y729705D03*
X357166Y724705D03*
X362166Y719705D03*
Y729705D03*
X347166Y734705D03*
X357166D03*
X342165Y894705D03*
X347165Y899705D03*
X352165Y894705D03*
X357165Y899705D03*
X362165Y894705D03*
X342165Y904705D03*
X347165Y909705D03*
X352165Y904705D03*
X357165Y909705D03*
X362165Y904705D03*
X342165Y1069705D03*
X352165D03*
X362165D03*
X342165Y1079705D03*
X347165Y1074705D03*
Y1084705D03*
X352165Y1079705D03*
X357165Y1074705D03*
Y1084705D03*
X362165Y1079705D03*
X342165Y1244705D03*
Y1254705D03*
X347165Y1249705D03*
Y1259705D03*
X352165Y1244705D03*
Y1254705D03*
X357165Y1249705D03*
Y1259705D03*
X362165Y1244705D03*
Y1254705D03*
X342165Y1419705D03*
Y1429705D03*
X347165Y1424705D03*
Y1434705D03*
X352165Y1419705D03*
Y1429705D03*
X357165Y1424705D03*
Y1434705D03*
X362165Y1419705D03*
Y1429705D03*
X342165Y1594705D03*
X347165Y1599705D03*
X352165Y1594705D03*
X357165Y1599705D03*
X362165Y1594705D03*
X342165Y1604705D03*
X347165Y1609705D03*
X352165Y1604705D03*
X357165Y1609705D03*
X362165Y1604705D03*
X342165Y1769705D03*
X352165D03*
X362165D03*
X342165Y1779705D03*
X347165Y1774705D03*
Y1784705D03*
X352165Y1779705D03*
X357165Y1774705D03*
Y1784705D03*
X362165Y1779705D03*
X342165Y1944705D03*
Y1954705D03*
X347165Y1949705D03*
Y1959705D03*
X352165Y1944705D03*
Y1954705D03*
X357165Y1949705D03*
Y1959705D03*
X362165Y1944705D03*
Y1954705D03*
G54D16*
X17480Y599901D03*
X9606D03*
X17480Y627264D03*
X9606D03*
X17480Y1471949D03*
X9606D03*
X17480Y1499311D03*
X9606D03*
G54D22*
X65354Y101180D03*
X55511Y105117D03*
X51574Y114960D03*
X55511Y124803D03*
X65354Y128740D03*
Y451180D03*
X55511Y455117D03*
X51574Y464960D03*
X55511Y474803D03*
X65354Y478740D03*
Y801180D03*
X55511Y805117D03*
X51574Y814960D03*
X55511Y824803D03*
X65354Y828740D03*
Y1151180D03*
X55511Y1155117D03*
X51574Y1164960D03*
X55511Y1174803D03*
X65354Y1178740D03*
Y1501180D03*
X55511Y1505117D03*
X51574Y1514960D03*
X55511Y1524803D03*
X65354Y1528740D03*
Y1851180D03*
X55511Y1855117D03*
X51574Y1864960D03*
X55511Y1874803D03*
X65354Y1878740D03*
X75197Y105117D03*
Y124803D03*
X79134Y114960D03*
Y464960D03*
X75197Y455117D03*
Y474803D03*
Y805117D03*
Y824803D03*
X79134Y814960D03*
Y1164960D03*
X75197Y1155117D03*
Y1174803D03*
Y1505117D03*
Y1524803D03*
X79134Y1514960D03*
Y1864960D03*
X75197Y1855117D03*
Y1874803D03*
X307086Y113385D03*
X297243Y117322D03*
X293306Y127165D03*
X297243Y137008D03*
X307086Y140945D03*
Y463385D03*
X297243Y467322D03*
X293306Y477165D03*
X297243Y487008D03*
X307086Y490945D03*
Y813385D03*
X297243Y817322D03*
X293306Y827165D03*
X297243Y837008D03*
X307086Y840945D03*
Y1329724D03*
X297243Y1333661D03*
X293306Y1343504D03*
X297243Y1353347D03*
X307086Y1357284D03*
Y1679724D03*
X297243Y1683661D03*
X293306Y1693504D03*
X297243Y1703347D03*
X307086Y1707284D03*
X307087Y2029723D03*
X297244Y2033660D03*
X293307Y2043503D03*
X297244Y2053346D03*
X307087Y2057283D03*
X320866Y127165D03*
X316929Y117322D03*
Y137008D03*
Y467322D03*
Y487008D03*
X320866Y477165D03*
Y827165D03*
X316929Y817322D03*
Y837008D03*
Y1333661D03*
Y1353347D03*
X320866Y1343504D03*
Y1693504D03*
X316929Y1683661D03*
Y1703347D03*
X316930Y2033660D03*
Y2053346D03*
X320867Y2043503D03*
G54D25*
X119920Y18071D03*
Y28071D03*
Y38071D03*
Y48071D03*
Y58071D03*
Y68071D03*
Y78071D03*
Y88071D03*
Y98071D03*
Y108071D03*
Y118071D03*
Y128071D03*
Y138071D03*
Y148071D03*
Y158071D03*
Y168071D03*
Y178071D03*
Y188071D03*
Y198071D03*
Y208071D03*
Y366102D03*
Y376102D03*
Y386102D03*
Y396102D03*
Y406102D03*
Y416102D03*
Y426102D03*
Y436102D03*
Y446102D03*
Y456102D03*
Y466102D03*
Y476102D03*
Y486102D03*
Y496102D03*
Y506102D03*
Y516102D03*
Y526102D03*
Y536102D03*
Y546102D03*
Y556102D03*
Y714134D03*
Y724134D03*
Y734134D03*
Y744134D03*
Y754134D03*
Y764134D03*
Y774134D03*
Y784134D03*
Y794134D03*
Y804134D03*
Y814134D03*
Y824134D03*
Y834134D03*
Y844134D03*
Y854134D03*
Y864134D03*
Y874134D03*
Y884134D03*
Y894134D03*
Y904134D03*
Y1062165D03*
Y1072165D03*
Y1082165D03*
Y1092165D03*
Y1102165D03*
Y1112165D03*
Y1122165D03*
Y1132165D03*
Y1142165D03*
Y1152165D03*
Y1162165D03*
Y1172165D03*
Y1182165D03*
Y1192165D03*
Y1202165D03*
Y1212165D03*
Y1222165D03*
Y1232165D03*
Y1242165D03*
Y1252165D03*
Y1410197D03*
Y1420197D03*
Y1430197D03*
Y1440197D03*
Y1450197D03*
Y1460197D03*
Y1470197D03*
Y1480197D03*
Y1490197D03*
Y1500197D03*
Y1510197D03*
Y1520197D03*
Y1530197D03*
Y1540197D03*
Y1550197D03*
Y1560197D03*
Y1570197D03*
Y1580197D03*
Y1590197D03*
Y1600197D03*
Y1758228D03*
Y1768228D03*
Y1778228D03*
Y1788228D03*
Y1798228D03*
Y1808228D03*
Y1818228D03*
Y1828228D03*
Y1838228D03*
Y1848228D03*
Y1858228D03*
Y1868228D03*
Y1878228D03*
Y1888228D03*
Y1898228D03*
Y1908228D03*
Y1918228D03*
Y1928228D03*
Y1938228D03*
Y1948228D03*
X139920Y28071D03*
Y18071D03*
Y58071D03*
Y48071D03*
Y38071D03*
Y78071D03*
Y68071D03*
Y98071D03*
Y88071D03*
Y128071D03*
Y118071D03*
Y108071D03*
Y148071D03*
Y138071D03*
Y178071D03*
Y168071D03*
Y158071D03*
Y198071D03*
Y188071D03*
Y208071D03*
Y366102D03*
Y396102D03*
Y386102D03*
Y376102D03*
Y416102D03*
Y406102D03*
Y436102D03*
Y426102D03*
Y466102D03*
Y456102D03*
Y446102D03*
Y486102D03*
Y476102D03*
Y516102D03*
Y506102D03*
Y496102D03*
Y536102D03*
Y526102D03*
Y556102D03*
Y546102D03*
Y734134D03*
Y724134D03*
Y714134D03*
Y754134D03*
Y744134D03*
Y774134D03*
Y764134D03*
Y804134D03*
Y794134D03*
Y784134D03*
Y824134D03*
Y814134D03*
Y854134D03*
Y844134D03*
Y834134D03*
Y874134D03*
Y864134D03*
Y904134D03*
Y894134D03*
Y884134D03*
Y1072165D03*
Y1062165D03*
Y1092165D03*
Y1082165D03*
Y1122165D03*
Y1112165D03*
Y1102165D03*
Y1142165D03*
Y1132165D03*
Y1162165D03*
Y1152165D03*
Y1192165D03*
Y1182165D03*
Y1172165D03*
Y1212165D03*
Y1202165D03*
Y1242165D03*
Y1232165D03*
Y1222165D03*
Y1252165D03*
Y1410197D03*
Y1430197D03*
Y1420197D03*
Y1460197D03*
Y1450197D03*
Y1440197D03*
Y1480197D03*
Y1470197D03*
Y1500197D03*
Y1490197D03*
Y1530197D03*
Y1520197D03*
Y1510197D03*
Y1550197D03*
Y1540197D03*
Y1580197D03*
Y1570197D03*
Y1560197D03*
Y1600197D03*
Y1590197D03*
Y1768228D03*
Y1758228D03*
Y1798228D03*
Y1788228D03*
Y1778228D03*
Y1818228D03*
Y1808228D03*
Y1838228D03*
Y1828228D03*
Y1868228D03*
Y1858228D03*
Y1848228D03*
Y1888228D03*
Y1878228D03*
Y1918228D03*
Y1908228D03*
Y1898228D03*
Y1938228D03*
Y1928228D03*
Y1948228D03*
G54D13*
X18995Y508701D03*
X23995Y518701D03*
X21495Y559882D03*
X11692D03*
X21495Y1571811D03*
X11692D03*
X23995Y1622992D03*
X18995Y1612992D03*
X28995Y508701D03*
X38995D03*
X48995D03*
X33995Y518701D03*
X43995D03*
X51495Y559882D03*
Y1571811D03*
X43995Y1622992D03*
X33995D03*
X48995Y1612992D03*
X38995D03*
X28995D03*
X53995Y518701D03*
X61298Y559882D03*
Y1571811D03*
X53995Y1622992D03*
X189762Y73105D03*
X190289Y152050D03*
X190357Y247568D03*
X190817Y331786D03*
X189761Y421732D03*
X190553Y506517D03*
X192888Y598130D03*
X190816Y681645D03*
X191846Y774526D03*
X191606Y856244D03*
X196311Y947202D03*
X195516Y1032544D03*
X191250Y1122856D03*
X191342Y1206233D03*
X191846Y1299104D03*
X190552Y1380966D03*
X189463Y1474162D03*
X191079Y1557277D03*
X192143Y1648177D03*
X191607Y1731351D03*
X191530Y1823227D03*
X190289Y1900420D03*
X192125Y1998730D03*
X191530Y2043388D03*
G54D15*
X5491Y528544D03*
Y1603149D03*
X67499Y528544D03*
Y1603149D03*
G54D17*
X15547Y707364D03*
Y723112D03*
Y730986D03*
X25389Y723112D03*
Y730986D03*
X7673Y719175D03*
Y727049D03*
X15547Y738860D03*
Y746734D03*
Y754608D03*
X25389Y738860D03*
Y746734D03*
Y754608D03*
X7673Y734923D03*
Y742797D03*
Y750671D03*
Y758545D03*
X15547Y762483D03*
Y770357D03*
Y778231D03*
X25389Y762483D03*
Y770357D03*
Y778231D03*
X7673Y766419D03*
Y774293D03*
Y782167D03*
X15547Y786105D03*
Y793979D03*
Y801853D03*
X25389Y786105D03*
Y793979D03*
Y801853D03*
X7673Y790041D03*
Y797915D03*
Y805790D03*
X15547Y809727D03*
Y817601D03*
Y825475D03*
X25389Y809727D03*
Y817601D03*
Y825475D03*
X7673Y813664D03*
Y821538D03*
Y829412D03*
X15547Y833349D03*
Y841223D03*
Y849097D03*
X25389Y833349D03*
Y841223D03*
Y849097D03*
X7673Y837286D03*
Y845160D03*
Y853034D03*
X15547Y856971D03*
Y864845D03*
Y872719D03*
X25389Y856971D03*
Y864845D03*
Y872719D03*
X7673Y860908D03*
Y868782D03*
Y876656D03*
X15547Y880593D03*
Y888467D03*
Y896341D03*
X25389Y880593D03*
Y888467D03*
Y896341D03*
X7673Y884530D03*
Y892404D03*
Y900278D03*
X15547Y904215D03*
Y912089D03*
Y919963D03*
X25389Y904215D03*
Y912089D03*
Y919963D03*
X7673Y908152D03*
Y916026D03*
Y923900D03*
X15547Y927837D03*
Y935711D03*
Y943585D03*
Y951459D03*
X25389Y927837D03*
Y935711D03*
Y943585D03*
Y951459D03*
X7673Y931774D03*
Y939648D03*
Y947522D03*
X15547Y959333D03*
Y967207D03*
Y975081D03*
X25389Y959333D03*
Y967207D03*
Y975081D03*
X7673Y955396D03*
Y963270D03*
Y971144D03*
Y979018D03*
Y994766D03*
X15547Y990829D03*
Y998703D03*
X25389Y990829D03*
Y998703D03*
X7673Y1002640D03*
Y1010514D03*
Y1018388D03*
X15547Y1006577D03*
Y1014451D03*
Y1022325D03*
X25389Y1006577D03*
Y1014451D03*
Y1022325D03*
X7673Y1026262D03*
X15547Y1030199D03*
X25389D03*
X15551Y1065629D03*
X25393D03*
X7677Y1061692D03*
Y1069566D03*
X15551Y1073503D03*
Y1081377D03*
Y1089251D03*
X25393Y1073503D03*
Y1081377D03*
Y1089251D03*
X7677Y1077440D03*
Y1085314D03*
Y1093188D03*
X15551Y1097125D03*
Y1104999D03*
Y1112873D03*
Y1120748D03*
X25393Y1097125D03*
Y1104999D03*
Y1112873D03*
Y1120748D03*
X7677Y1101062D03*
Y1108936D03*
Y1116810D03*
X15551Y1128622D03*
Y1136496D03*
Y1144370D03*
X25393Y1128622D03*
Y1136496D03*
Y1144370D03*
X7677Y1124684D03*
Y1132558D03*
Y1140432D03*
X15551Y1152244D03*
Y1160118D03*
Y1167992D03*
X25393Y1152244D03*
Y1160118D03*
Y1167992D03*
X7677Y1148306D03*
Y1156180D03*
Y1164055D03*
X15551Y1175866D03*
Y1183740D03*
Y1191614D03*
X25393Y1175866D03*
Y1183740D03*
Y1191614D03*
X7677Y1171929D03*
Y1179803D03*
Y1187677D03*
X15551Y1199488D03*
Y1207362D03*
Y1215236D03*
X25393Y1199488D03*
Y1207362D03*
Y1215236D03*
X7677Y1195551D03*
Y1203425D03*
Y1211299D03*
X15551Y1223110D03*
Y1230984D03*
Y1238858D03*
X25393Y1223110D03*
Y1230984D03*
Y1238858D03*
X7677Y1219173D03*
Y1227047D03*
Y1234921D03*
X15551Y1246732D03*
Y1254606D03*
Y1262480D03*
X25393Y1246732D03*
Y1254606D03*
Y1262480D03*
X7677Y1242795D03*
Y1250669D03*
Y1258543D03*
X15551Y1270354D03*
Y1278228D03*
Y1286102D03*
X25393Y1270354D03*
Y1278228D03*
Y1286102D03*
X7677Y1266417D03*
Y1274291D03*
Y1282165D03*
X15551Y1293976D03*
Y1301850D03*
Y1309724D03*
X25393Y1293976D03*
Y1301850D03*
Y1309724D03*
X7677Y1290039D03*
Y1297913D03*
Y1305787D03*
Y1313661D03*
X15551Y1317598D03*
Y1325472D03*
Y1333346D03*
X25393Y1317598D03*
Y1325472D03*
Y1333346D03*
X7677Y1321535D03*
Y1329409D03*
Y1337283D03*
Y1353031D03*
Y1360905D03*
X15551Y1349094D03*
Y1356968D03*
X25393Y1349094D03*
Y1356968D03*
X7677Y1368779D03*
Y1376653D03*
Y1384527D03*
X15551Y1364842D03*
Y1372716D03*
Y1380590D03*
X25393Y1364842D03*
Y1372716D03*
Y1380590D03*
X15551Y1388464D03*
X25393D03*
X33263Y727049D03*
Y734923D03*
Y742797D03*
Y750671D03*
Y758545D03*
Y766419D03*
Y774293D03*
Y782167D03*
Y790041D03*
Y797915D03*
Y805790D03*
Y813664D03*
Y821538D03*
Y829412D03*
Y837286D03*
Y845160D03*
Y853034D03*
Y860908D03*
Y868782D03*
Y876656D03*
Y884530D03*
Y892404D03*
Y900278D03*
Y908152D03*
Y916026D03*
Y923900D03*
Y931774D03*
Y939648D03*
Y947522D03*
Y955396D03*
Y963270D03*
Y971144D03*
Y979018D03*
Y994766D03*
Y1002640D03*
Y1010514D03*
Y1018388D03*
Y1026262D03*
X33267Y1061692D03*
Y1069566D03*
Y1077440D03*
Y1085314D03*
Y1093188D03*
Y1101062D03*
Y1108936D03*
Y1116810D03*
Y1124684D03*
Y1132558D03*
Y1140432D03*
Y1148306D03*
Y1156180D03*
Y1164055D03*
Y1171929D03*
Y1179803D03*
Y1187677D03*
Y1195551D03*
Y1203425D03*
Y1211299D03*
Y1219173D03*
Y1227047D03*
Y1234921D03*
Y1242795D03*
Y1250669D03*
Y1258543D03*
Y1266417D03*
Y1274291D03*
Y1282165D03*
Y1290039D03*
Y1297913D03*
Y1305787D03*
Y1313661D03*
Y1321535D03*
Y1329409D03*
Y1337283D03*
Y1353031D03*
Y1360905D03*
Y1368779D03*
Y1376653D03*
Y1384527D03*
G54D10*
X17735Y24953D03*
X27735D03*
X22735Y34953D03*
Y216976D03*
X27735Y206976D03*
X17735D03*
Y233811D03*
X27735D03*
X22735Y243811D03*
X27735Y415834D03*
X17735D03*
X22735Y425834D03*
Y1957291D03*
X27735Y1947291D03*
X17735D03*
X22735Y2061661D03*
X27735Y2051661D03*
X17735D03*
X37735Y24953D03*
X47735D03*
X32735Y34953D03*
X42735D03*
Y216976D03*
X32735D03*
X47735Y206976D03*
X37735D03*
Y233811D03*
X47735D03*
X32735Y243811D03*
X42735D03*
X47735Y415834D03*
X37735D03*
X42735Y425834D03*
X32735D03*
X42735Y1957291D03*
X32735D03*
X47735Y1947291D03*
X37735D03*
X42735Y2061661D03*
X32735D03*
X47735Y2051661D03*
X37735D03*
X52735Y34953D03*
Y216976D03*
Y243811D03*
Y425834D03*
Y1957291D03*
Y2061661D03*
G54D20*
X23402Y1668874D03*
Y1685410D03*
Y1701945D03*
Y1718480D03*
Y1735016D03*
Y1751551D03*
Y1768087D03*
Y1784622D03*
Y1817693D03*
Y1801158D03*
X45056Y1668874D03*
Y1718480D03*
Y1768087D03*
Y1817693D03*
G54D29*
X165975Y265783D03*
Y296140D03*
Y286803D03*
Y276298D03*
Y303868D03*
X157272Y604773D03*
Y633416D03*
Y613574D03*
Y624079D03*
Y641144D03*
X166699Y972924D03*
Y983439D03*
Y993944D03*
X166424Y1011298D03*
Y1003570D03*
X155749Y1307733D03*
Y1328753D03*
Y1318248D03*
Y1338090D03*
Y1345818D03*
X158492Y1667763D03*
Y1657248D03*
Y1695333D03*
Y1687605D03*
Y1678268D03*
X219214Y1287272D03*
X222732Y153964D03*
X232700D03*
X222732Y161692D03*
X232700Y170131D03*
Y161692D03*
X239746Y407393D03*
Y396878D03*
Y417898D03*
X243980Y754782D03*
X234012D03*
X243980Y762510D03*
Y770949D03*
X234012Y762510D03*
X224573Y2031480D03*
X234541D03*
X224573Y2020965D03*
X234541D03*
X224573Y2059050D03*
X234541Y2051322D03*
Y2059050D03*
X224573Y2041985D03*
Y2051322D03*
X234541Y2041985D03*
Y2067489D03*
X256566Y54944D03*
X264104D03*
X256566Y45572D03*
X264104D03*
X256566Y65449D03*
X264104D03*
X264861Y153964D03*
Y170131D03*
Y161692D03*
X264596Y268188D03*
Y259749D03*
Y252021D03*
X248714Y407536D03*
Y397021D03*
Y418041D03*
X263174Y855159D03*
Y862887D03*
Y871326D03*
X261219Y1124364D03*
Y1134879D03*
X251251Y1124364D03*
Y1134879D03*
X261219Y1145384D03*
X251251D03*
X259581Y1272430D03*
Y1282945D03*
Y1293450D03*
Y1302787D03*
Y1310515D03*
Y1318954D03*
X254718Y1697613D03*
Y1687108D03*
Y1676593D03*
X254457Y1722140D03*
X254718Y1714678D03*
Y1706950D03*
X278944Y601282D03*
Y609010D03*
Y617449D03*
X274399Y974386D03*
Y990553D03*
Y982114D03*
X286721Y1184312D03*
Y1192040D03*
X278182Y1184455D03*
Y1192183D03*
X286721Y1200479D03*
X273342Y1668347D03*
Y1652180D03*
Y1659908D03*
X270115Y2051322D03*
Y2059050D03*
Y2067489D03*
X300537Y516309D03*
Y524037D03*
Y532476D03*
X292569Y524323D03*
Y516595D03*
X304146Y661258D03*
Y652457D03*
Y681100D03*
Y671763D03*
Y688828D03*
Y697267D03*
X307194Y1020657D03*
X307078Y1007303D03*
X307274Y1001286D03*
X307143Y1014094D03*
X307129Y1027081D03*
X306999Y1033718D03*
X311936Y1192253D03*
Y1184525D03*
Y1200692D03*
X332775Y318634D03*
X332693Y311980D03*
X332775Y335272D03*
Y342461D03*
Y325935D03*
X332685Y348655D03*
X325139Y516632D03*
Y524360D03*
Y532799D03*
G54D30*
X165975Y312307D03*
X157272Y649583D03*
X166424Y1019737D03*
X155749Y1354257D03*
X158492Y1703772D03*
X243741Y153964D03*
Y170131D03*
Y161692D03*
X222732Y170131D03*
X234012Y770949D03*
X235465Y1301975D03*
X235600Y1308924D03*
X242961Y1301975D03*
X243096Y1308924D03*
X235465Y1294491D03*
X242961D03*
X235429Y1324285D03*
Y1332321D03*
X242925Y1324285D03*
Y1332321D03*
X235429Y1316842D03*
X242925D03*
X235429Y1339840D03*
X242925D03*
X224573Y2067489D03*
X253083Y153964D03*
Y170131D03*
Y161692D03*
X264596Y221664D03*
X252818D03*
X264596Y242684D03*
Y232179D03*
X252818Y242684D03*
Y232179D03*
Y268188D03*
Y252021D03*
Y259749D03*
X266040Y407146D03*
Y396631D03*
Y417651D03*
X257572Y396630D03*
Y407145D03*
Y417650D03*
X267166Y581440D03*
Y572639D03*
Y609010D03*
Y601282D03*
Y591945D03*
Y617449D03*
X255021Y754782D03*
Y762510D03*
Y770949D03*
X251396Y862887D03*
Y855159D03*
Y871326D03*
X262766Y949344D03*
Y967106D03*
Y959859D03*
X262621Y974386D03*
Y990553D03*
Y982114D03*
X261564Y1621823D03*
Y1642843D03*
Y1632338D03*
Y1668347D03*
Y1659908D03*
Y1652180D03*
X265759Y1697613D03*
Y1676593D03*
Y1687108D03*
X265498Y1722140D03*
X265759Y1714678D03*
Y1706950D03*
X258639Y1819074D03*
Y1812119D03*
Y1805203D03*
X258459Y1826219D03*
Y1840090D03*
Y1833135D03*
X245582Y2031480D03*
Y2020965D03*
X258337D03*
Y2031480D03*
X245582Y2041985D03*
Y2051322D03*
Y2059050D03*
X258337Y2051322D03*
Y2059050D03*
Y2041985D03*
Y2067489D03*
X245582D03*
X288102Y54944D03*
Y45572D03*
X271572Y54944D03*
X279754D03*
X271572Y45572D03*
X279754D03*
X288102Y65449D03*
X271572D03*
X279754D03*
X274531Y407289D03*
Y396774D03*
Y417794D03*
X278944Y581440D03*
Y572639D03*
Y591945D03*
X274544Y949344D03*
Y967106D03*
Y959859D03*
X279015Y1124077D03*
X288363Y1123935D03*
X279015Y1134592D03*
X288363Y1134450D03*
X269975Y1134735D03*
Y1124220D03*
X288363Y1144955D03*
X279015Y1145097D03*
X269975Y1145240D03*
X278182Y1200622D03*
X270622Y1282945D03*
Y1272430D03*
Y1293450D03*
Y1302787D03*
Y1310515D03*
Y1318954D03*
X273342Y1621823D03*
Y1642843D03*
Y1632338D03*
X270115Y2031480D03*
Y2020965D03*
Y2041985D03*
X307966Y516419D03*
Y524147D03*
Y532586D03*
X292569Y532762D03*
X315187Y652457D03*
Y661258D03*
Y681100D03*
Y671763D03*
Y688828D03*
Y697267D03*
X303159Y1184526D03*
Y1192254D03*
X294691Y1184526D03*
Y1192254D03*
X303159Y1200693D03*
X294691D03*
X301066Y1472954D03*
X300886Y1480099D03*
X301066Y1465999D03*
Y1459083D03*
X300886Y1493970D03*
Y1487015D03*
X316791Y524432D03*
Y516704D03*
Y532871D03*
X318235Y1020657D03*
X318315Y1001286D03*
X318119Y1007303D03*
X318184Y1014094D03*
X318170Y1027081D03*
X318040Y1033718D03*
X343816Y318634D03*
X343734Y311980D03*
X343816Y335272D03*
Y342461D03*
Y325935D03*
X343726Y348655D03*
G54D37*
X307086Y1883071D03*
G54D19*
X20468Y696341D03*
Y984333D03*
X20472Y1054606D03*
Y1342598D03*
G54D12*
X12735Y59953D03*
Y181976D03*
Y268811D03*
Y390834D03*
Y1922291D03*
Y2026661D03*
X57735Y59953D03*
Y181976D03*
Y268811D03*
Y390834D03*
Y1922291D03*
Y2026661D03*
G54D36*
X307086Y308267D03*
G54D14*
X13995Y543701D03*
Y1587992D03*
X58995Y543701D03*
Y1587992D03*
G54D27*
X163385Y27205D03*
Y202205D03*
Y377205D03*
X163386Y552205D03*
Y727205D03*
X163385Y902205D03*
Y1077205D03*
Y1252205D03*
Y1427205D03*
Y1602205D03*
Y1777205D03*
Y1952205D03*
X373385Y32520D03*
Y207520D03*
Y382520D03*
X373386Y557520D03*
Y732520D03*
X373385Y907520D03*
Y1082520D03*
Y1257520D03*
Y1432520D03*
Y1607520D03*
Y1782520D03*
Y1957520D03*
G54D38*
X359842Y78780D03*
Y253780D03*
Y428779D03*
Y603779D03*
Y778780D03*
Y953780D03*
Y1128779D03*
Y1303780D03*
Y1478780D03*
Y1653780D03*
Y1828779D03*
Y2003780D03*
G54D18*
X25389Y707364D03*
X7673Y703427D03*
X15547Y715238D03*
X25389D03*
X7673Y711301D03*
X33263Y703427D03*
Y711301D03*
Y719175D03*
G54D33*
X219214Y1301975D03*
X219349Y1308924D03*
X219214Y1294491D03*
X219178Y1324285D03*
Y1332321D03*
Y1316842D03*
Y1339840D03*
X226642Y1287272D03*
Y1301975D03*
X226777Y1308924D03*
X226642Y1294491D03*
X226606Y1324285D03*
Y1332321D03*
Y1316842D03*
Y1339840D03*
G54D35*
X263939Y1548010D03*
Y1534139D03*
Y1541055D03*
X250468Y1819074D03*
Y1812119D03*
Y1805203D03*
X267396Y1819077D03*
Y1805206D03*
Y1812122D03*
X250288Y1826219D03*
X267037Y1826222D03*
Y1833138D03*
Y1840093D03*
X250288Y1833135D03*
Y1840090D03*
X278400Y1548190D03*
X271534Y1548010D03*
X285995Y1548190D03*
X278400Y1534319D03*
Y1541235D03*
X271534Y1534139D03*
Y1541055D03*
X285995Y1534319D03*
Y1541235D03*
X309823Y1472957D03*
X309464Y1480102D03*
X309823Y1466002D03*
Y1459086D03*
X292715Y1480099D03*
X292895Y1472954D03*
Y1459083D03*
Y1465999D03*
X309464Y1493973D03*
Y1487018D03*
X292715Y1487015D03*
Y1493970D03*
X292754Y1917148D03*
X300349D03*
X292754Y1910232D03*
X300349D03*
X307215Y1910412D03*
X314810D03*
Y1917328D03*
X307215D03*
X292754Y1924103D03*
X300349D03*
X314810Y1924283D03*
X307215D03*
G54D34*
X253385Y21890D03*
Y32520D03*
X263385Y21890D03*
Y32520D03*
X253385Y196890D03*
X263385D03*
X253385Y207520D03*
X263385D03*
X253385Y371890D03*
X263385D03*
X253385Y382520D03*
X263385D03*
X253386Y546890D03*
Y557520D03*
X263386Y546890D03*
Y557520D03*
X253386Y721890D03*
Y732520D03*
X263386Y721890D03*
Y732520D03*
X253385Y896890D03*
X263385D03*
X253385Y907520D03*
X263385D03*
X253385Y1071890D03*
X263385D03*
X253385Y1082520D03*
X263385D03*
X253385Y1246890D03*
Y1257520D03*
X263385Y1246890D03*
Y1257520D03*
X253385Y1421890D03*
Y1432520D03*
X263385Y1421890D03*
Y1432520D03*
X253385Y1596890D03*
X263385D03*
X253385Y1607520D03*
X263385D03*
X253385Y1771890D03*
X263385D03*
X253385Y1782520D03*
X263385D03*
X253385Y1946890D03*
Y1957520D03*
X263385Y1946890D03*
Y1957520D03*
X273385Y21890D03*
Y32520D03*
X283385Y21890D03*
Y32520D03*
X273385Y196890D03*
X283385D03*
X273385Y207520D03*
X283385D03*
X273385Y371890D03*
X283385D03*
X273385Y382520D03*
X283385D03*
X273386Y546890D03*
Y557520D03*
X283386Y546890D03*
Y557520D03*
X273386Y721890D03*
Y732520D03*
X283386Y721890D03*
Y732520D03*
X273385Y896890D03*
X283385D03*
X273385Y907520D03*
X283385D03*
X273385Y1071890D03*
X283385D03*
X273385Y1082520D03*
X283385D03*
X273385Y1246890D03*
Y1257520D03*
X283385Y1246890D03*
Y1257520D03*
X273385Y1421890D03*
Y1432520D03*
X283385Y1421890D03*
Y1432520D03*
X273385Y1596890D03*
X283385D03*
X273385Y1607520D03*
X283385D03*
X273385Y1771890D03*
X283385D03*
X273385Y1782520D03*
X283385D03*
X273385Y1946890D03*
Y1957520D03*
X283385Y1946890D03*
Y1957520D03*
X293385Y21890D03*
Y32520D03*
X303385Y21890D03*
Y32520D03*
X313385D03*
Y21890D03*
X293385Y196890D03*
X303385D03*
X313385D03*
X293385Y207520D03*
X303385D03*
X313385D03*
X293385Y371890D03*
X303385D03*
X313385D03*
X293385Y382520D03*
X303385D03*
X313385D03*
X293386Y546890D03*
Y557520D03*
X303386Y546890D03*
Y557520D03*
X313386D03*
Y546890D03*
X293386Y721890D03*
Y732520D03*
X303386Y721890D03*
Y732520D03*
X313386D03*
Y721890D03*
X293385Y896890D03*
X303385D03*
X313385D03*
X293385Y907520D03*
X303385D03*
X313385D03*
X293385Y1071890D03*
X303385D03*
X313385D03*
X293385Y1082520D03*
X303385D03*
X313385D03*
X293385Y1246890D03*
Y1257520D03*
X303385Y1246890D03*
Y1257520D03*
X313385D03*
Y1246890D03*
X293385Y1421890D03*
Y1432520D03*
X303385Y1421890D03*
Y1432520D03*
X313385D03*
Y1421890D03*
X293385Y1596890D03*
X303385D03*
X313385D03*
X293385Y1607520D03*
X303385D03*
X313385D03*
X293385Y1771890D03*
X303385D03*
X313385D03*
X293385Y1782520D03*
X303385D03*
X313385D03*
X293385Y1946890D03*
Y1957520D03*
X303385Y1946890D03*
Y1957520D03*
X313385D03*
Y1946890D03*
X323385Y32520D03*
Y21890D03*
Y196890D03*
Y207520D03*
Y371890D03*
Y382520D03*
X323386Y557520D03*
Y546890D03*
Y732520D03*
Y721890D03*
X323385Y896890D03*
Y907520D03*
Y1071890D03*
Y1082520D03*
Y1257520D03*
Y1246890D03*
Y1432520D03*
Y1421890D03*
Y1596890D03*
Y1607520D03*
Y1771890D03*
Y1782520D03*
Y1957520D03*
Y1946890D03*
G54D23*
X65354Y114960D03*
Y464960D03*
Y814960D03*
Y1164960D03*
Y1514960D03*
Y1864960D03*
X307086Y127165D03*
Y477165D03*
Y827165D03*
Y1343504D03*
Y1693504D03*
X307087Y2043503D03*
G54D24*
X59127Y1257647D03*
X58356Y1279812D03*
X58416Y1272383D03*
X161339Y88108D03*
X161517Y436119D03*
X161479Y784141D03*
X161844Y1828225D03*
X292614Y1864565D03*
X323403Y1172804D03*
G54D26*
X119920Y218071D03*
Y228071D03*
Y238071D03*
Y248071D03*
Y258071D03*
Y268071D03*
Y278071D03*
Y288071D03*
Y298071D03*
Y308071D03*
Y318071D03*
Y328071D03*
Y566102D03*
Y576102D03*
Y586102D03*
Y596102D03*
Y606102D03*
Y616102D03*
Y626102D03*
Y636102D03*
Y646102D03*
Y656102D03*
Y666102D03*
Y676102D03*
Y914134D03*
Y924134D03*
Y934134D03*
Y944134D03*
Y954134D03*
Y964134D03*
Y974134D03*
Y984134D03*
Y994134D03*
Y1004134D03*
Y1014134D03*
Y1024134D03*
Y1262165D03*
Y1272165D03*
Y1282165D03*
Y1292165D03*
Y1302165D03*
Y1312165D03*
Y1322165D03*
Y1332165D03*
Y1342165D03*
Y1352165D03*
Y1362165D03*
Y1372165D03*
Y1610197D03*
Y1620197D03*
Y1630197D03*
Y1640197D03*
Y1650197D03*
Y1660197D03*
Y1670197D03*
Y1680197D03*
Y1690197D03*
Y1700197D03*
Y1710197D03*
Y1720197D03*
Y1958228D03*
Y1968228D03*
Y1978228D03*
Y1988228D03*
Y1998228D03*
Y2008228D03*
Y2018228D03*
Y2028228D03*
Y2038228D03*
Y2048228D03*
Y2058228D03*
Y2068228D03*
X139920Y228071D03*
Y218071D03*
Y248071D03*
Y238071D03*
Y268071D03*
Y258071D03*
Y298071D03*
Y288071D03*
Y278071D03*
Y318071D03*
Y308071D03*
Y328071D03*
Y566102D03*
Y586102D03*
Y576102D03*
Y606102D03*
Y596102D03*
Y636102D03*
Y626102D03*
Y616102D03*
Y656102D03*
Y646102D03*
Y676102D03*
Y666102D03*
Y924134D03*
Y914134D03*
Y944134D03*
Y934134D03*
Y974134D03*
Y964134D03*
Y954134D03*
Y994134D03*
Y984134D03*
Y1024134D03*
Y1014134D03*
Y1004134D03*
Y1262165D03*
Y1282165D03*
Y1272165D03*
Y1312165D03*
Y1302165D03*
Y1292165D03*
Y1332165D03*
Y1322165D03*
Y1362165D03*
Y1352165D03*
Y1342165D03*
Y1372165D03*
Y1620197D03*
Y1610197D03*
Y1650197D03*
Y1640197D03*
Y1630197D03*
Y1670197D03*
Y1660197D03*
Y1700197D03*
Y1690197D03*
Y1680197D03*
Y1720197D03*
Y1710197D03*
Y1958228D03*
Y1988228D03*
Y1978228D03*
Y1968228D03*
Y2008228D03*
Y1998228D03*
Y2038228D03*
Y2028228D03*
Y2018228D03*
Y2058228D03*
Y2048228D03*
Y2068228D03*
G54D32*
X203542Y73105D03*
X204069Y152050D03*
X204137Y247568D03*
X204597Y331786D03*
X203541Y421732D03*
X204333Y506517D03*
X206668Y598130D03*
X204596Y681645D03*
X205626Y774526D03*
X205386Y856244D03*
X210091Y947202D03*
X209296Y1032544D03*
X205030Y1122856D03*
X205122Y1206233D03*
X205626Y1299104D03*
X204332Y1380966D03*
X203243Y1474162D03*
X204859Y1557277D03*
X205923Y1648177D03*
X205387Y1731351D03*
X205310Y1823227D03*
X204069Y1900420D03*
X205905Y1998730D03*
X205310Y2043388D03*
G54D21*
X45056Y1685410D03*
Y1701945D03*
Y1735016D03*
Y1751551D03*
Y1784622D03*
Y1801158D03*
%LPC*%
G75*
G54D39*
G01X-723776Y2987387D02*
Y-376795D01*
Y-489221D01*
X1782976D01*
Y-376795D01*
Y2987387D01*
X-723776D01*
G01X-4000Y-62500D02*
Y-137500D01*
X496000D01*
Y-62500D01*
X-4000D01*
G01X8000Y-127500D02*
Y-132500D01*
G01X6543Y-127500D02*
X9457D01*
G01X14367Y-132500D02*
X11833D01*
Y-127500D01*
X14367D01*
G01X13353Y-129917D02*
X11833D01*
G01X16933Y-127500D02*
Y-132500D01*
X19467D01*
G01X23300Y-132667D02*
X23173Y-132583D01*
Y-132417D01*
X23300Y-132333D01*
X23427Y-132417D01*
Y-132583D01*
X23300Y-132667D01*
G01Y-130417D02*
X23173Y-130333D01*
Y-130167D01*
X23300Y-130083D01*
X23427Y-130167D01*
Y-130333D01*
X23300Y-130417D01*
G01X28083Y-134167D02*
X27450Y-133333D01*
X27133Y-132500D01*
Y-129167D01*
X27450Y-128333D01*
X28083Y-127500D01*
G01X33500D02*
X32993Y-127667D01*
X32613Y-128083D01*
X32360Y-128583D01*
X32170Y-129250D01*
X32107Y-130000D01*
X32170Y-130750D01*
X32360Y-131417D01*
X32613Y-131917D01*
X32993Y-132333D01*
X33500Y-132500D01*
X34007Y-132333D01*
X34387Y-131917D01*
X34640Y-131417D01*
X34830Y-130750D01*
X34893Y-130000D01*
X34830Y-129250D01*
X34640Y-128583D01*
X34387Y-128083D01*
X34007Y-127667D01*
X33500Y-127500D01*
G01X37207Y-131500D02*
X37587Y-132083D01*
X38093Y-132417D01*
X38663Y-132500D01*
X39170Y-132417D01*
X39677Y-132000D01*
X39993Y-131500D01*
X40057Y-131000D01*
X39930Y-130417D01*
X39487Y-130000D01*
X39043Y-129833D01*
X38473D01*
G01X39043D02*
X39423Y-129583D01*
X39740Y-129167D01*
X39867Y-128667D01*
X39740Y-128167D01*
X39423Y-127750D01*
X38853Y-127500D01*
X38283Y-127583D01*
X37713Y-127917D01*
G01X44017Y-134167D02*
X44650Y-133333D01*
X44967Y-132500D01*
Y-129167D01*
X44650Y-128333D01*
X44017Y-127500D01*
G01X47407Y-131500D02*
X47787Y-132083D01*
X48293Y-132417D01*
X48863Y-132500D01*
X49370Y-132417D01*
X49877Y-132000D01*
X50193Y-131500D01*
X50257Y-131000D01*
X50130Y-130417D01*
X49687Y-130000D01*
X49243Y-129833D01*
X48673D01*
G01X49243D02*
X49623Y-129583D01*
X49940Y-129167D01*
X50067Y-128667D01*
X49940Y-128167D01*
X49623Y-127750D01*
X49053Y-127500D01*
X48483Y-127583D01*
X47913Y-127917D01*
G01X52697Y-128333D02*
X53077Y-127833D01*
X53520Y-127583D01*
X54027Y-127500D01*
X54660Y-127667D01*
X55103Y-128083D01*
X55230Y-128583D01*
X55167Y-129083D01*
X54913Y-129500D01*
X53647Y-130333D01*
X53077Y-130917D01*
X52697Y-131750D01*
X52570Y-132500D01*
X55230D01*
G01X58873D02*
X59000Y-131417D01*
X59190Y-130500D01*
X59443Y-129667D01*
X59760Y-128750D01*
X60267Y-127500D01*
X57733D01*
G01X63277Y-130833D02*
X64923D01*
G01X67997Y-128333D02*
X68377Y-127833D01*
X68820Y-127583D01*
X69327Y-127500D01*
X69960Y-127667D01*
X70403Y-128083D01*
X70530Y-128583D01*
X70467Y-129083D01*
X70213Y-129500D01*
X68947Y-130333D01*
X68377Y-130917D01*
X67997Y-131750D01*
X67870Y-132500D01*
X70530D01*
G01X72907Y-131500D02*
X73287Y-132083D01*
X73793Y-132417D01*
X74363Y-132500D01*
X74870Y-132417D01*
X75377Y-132000D01*
X75693Y-131500D01*
X75757Y-131000D01*
X75630Y-130417D01*
X75187Y-130000D01*
X74743Y-129833D01*
X74173D01*
G01X74743D02*
X75123Y-129583D01*
X75440Y-129167D01*
X75567Y-128667D01*
X75440Y-128167D01*
X75123Y-127750D01*
X74553Y-127500D01*
X73983Y-127583D01*
X73413Y-127917D01*
G01X80160Y-132500D02*
Y-127500D01*
X77817Y-131083D01*
X80983D01*
G01X83107Y-131750D02*
X83487Y-132167D01*
X83930Y-132417D01*
X84500Y-132500D01*
X85070Y-132333D01*
X85513Y-132000D01*
X85830Y-131417D01*
X85893Y-130750D01*
X85767Y-130083D01*
X85450Y-129667D01*
X85007Y-129333D01*
X84563Y-129250D01*
X84120Y-129333D01*
X83550Y-129667D01*
X83740Y-127500D01*
X85450D01*
G01X93497Y-132500D02*
Y-127500D01*
X95903D01*
G01X95017Y-129917D02*
X93497D01*
G01X98217Y-132500D02*
X99800Y-127500D01*
X101383Y-132500D01*
G01X100813Y-130750D02*
X98787D01*
G01X103570Y-132500D02*
X106230Y-127500D01*
G01X103570D02*
X106230Y-132500D01*
G01X110000Y-132667D02*
X109873Y-132583D01*
Y-132417D01*
X110000Y-132333D01*
X110127Y-132417D01*
Y-132583D01*
X110000Y-132667D01*
G01Y-130417D02*
X109873Y-130333D01*
Y-130167D01*
X110000Y-130083D01*
X110127Y-130167D01*
Y-130333D01*
X110000Y-130417D01*
G01X114783Y-134167D02*
X114150Y-133333D01*
X113833Y-132500D01*
Y-129167D01*
X114150Y-128333D01*
X114783Y-127500D01*
G01X120200D02*
X119693Y-127667D01*
X119313Y-128083D01*
X119060Y-128583D01*
X118870Y-129250D01*
X118807Y-130000D01*
X118870Y-130750D01*
X119060Y-131417D01*
X119313Y-131917D01*
X119693Y-132333D01*
X120200Y-132500D01*
X120707Y-132333D01*
X121087Y-131917D01*
X121340Y-131417D01*
X121530Y-130750D01*
X121593Y-130000D01*
X121530Y-129250D01*
X121340Y-128583D01*
X121087Y-128083D01*
X120707Y-127667D01*
X120200Y-127500D01*
G01X123907Y-131500D02*
X124287Y-132083D01*
X124793Y-132417D01*
X125363Y-132500D01*
X125870Y-132417D01*
X126377Y-132000D01*
X126693Y-131500D01*
X126757Y-131000D01*
X126630Y-130417D01*
X126187Y-130000D01*
X125743Y-129833D01*
X125173D01*
G01X125743D02*
X126123Y-129583D01*
X126440Y-129167D01*
X126567Y-128667D01*
X126440Y-128167D01*
X126123Y-127750D01*
X125553Y-127500D01*
X124983Y-127583D01*
X124413Y-127917D01*
G01X130717Y-134167D02*
X131350Y-133333D01*
X131667Y-132500D01*
Y-129167D01*
X131350Y-128333D01*
X130717Y-127500D01*
G01X134107Y-131500D02*
X134487Y-132083D01*
X134993Y-132417D01*
X135563Y-132500D01*
X136070Y-132417D01*
X136577Y-132000D01*
X136893Y-131500D01*
X136957Y-131000D01*
X136830Y-130417D01*
X136387Y-130000D01*
X135943Y-129833D01*
X135373D01*
G01X135943D02*
X136323Y-129583D01*
X136640Y-129167D01*
X136767Y-128667D01*
X136640Y-128167D01*
X136323Y-127750D01*
X135753Y-127500D01*
X135183Y-127583D01*
X134613Y-127917D01*
G01X139523Y-131917D02*
X139967Y-132333D01*
X140473Y-132500D01*
X140980Y-132333D01*
X141423Y-131833D01*
X141740Y-131083D01*
X141867Y-130333D01*
Y-129417D01*
X141740Y-128667D01*
X141423Y-128000D01*
X141043Y-127667D01*
X140600Y-127500D01*
X140093Y-127667D01*
X139713Y-128000D01*
X139460Y-128500D01*
X139333Y-129167D01*
X139460Y-129750D01*
X139777Y-130333D01*
X140157Y-130667D01*
X140600Y-130750D01*
X141107Y-130583D01*
X141487Y-130167D01*
X141867Y-129417D01*
G01X145573Y-132500D02*
X145700Y-131417D01*
X145890Y-130500D01*
X146143Y-129667D01*
X146460Y-128750D01*
X146967Y-127500D01*
X144433D01*
G01X149977Y-130833D02*
X151623D01*
G01X154507Y-131500D02*
X154887Y-132083D01*
X155393Y-132417D01*
X155963Y-132500D01*
X156470Y-132417D01*
X156977Y-132000D01*
X157293Y-131500D01*
X157357Y-131000D01*
X157230Y-130417D01*
X156787Y-130000D01*
X156343Y-129833D01*
X155773D01*
G01X156343D02*
X156723Y-129583D01*
X157040Y-129167D01*
X157167Y-128667D01*
X157040Y-128167D01*
X156723Y-127750D01*
X156153Y-127500D01*
X155583Y-127583D01*
X155013Y-127917D01*
G01X159797Y-130417D02*
X160240Y-129833D01*
X160620Y-129500D01*
X161127Y-129333D01*
X161570Y-129500D01*
X161887Y-129833D01*
X162140Y-130333D01*
X162203Y-130917D01*
X162140Y-131417D01*
X161887Y-131917D01*
X161507Y-132333D01*
X161063Y-132500D01*
X160557Y-132333D01*
X160113Y-131833D01*
X159860Y-131083D01*
X159797Y-130250D01*
X159923Y-129167D01*
X160113Y-128583D01*
X160430Y-128000D01*
X160873Y-127583D01*
X161317Y-127500D01*
X161760Y-127667D01*
X162077Y-128083D01*
G01X166100Y-132500D02*
Y-127500D01*
X165340Y-128500D01*
G01Y-132500D02*
X166860D01*
G01X171960D02*
Y-127500D01*
X169617Y-131083D01*
X172783D01*
G01X191000Y-62500D02*
Y-137500D01*
G01Y-112500D02*
X294000D01*
Y-87500D01*
G01X191000D02*
X294000D01*
G01X301507Y-122500D02*
Y-117500D01*
X302773D01*
X303280Y-117750D01*
X303660Y-118083D01*
X303977Y-118583D01*
X304230Y-119167D01*
X304293Y-120000D01*
X304230Y-120833D01*
X303977Y-121417D01*
X303660Y-121917D01*
X303280Y-122250D01*
X302773Y-122500D01*
X301507D01*
G01X306417D02*
X308000Y-117500D01*
X309583Y-122500D01*
G01X309013Y-120750D02*
X306987D01*
G01X313100Y-117500D02*
Y-122500D01*
G01X311643Y-117500D02*
X314557D01*
G01X319467Y-122500D02*
X316933D01*
Y-117500D01*
X319467D01*
G01X318453Y-119917D02*
X316933D01*
G01X323300Y-122667D02*
X323173Y-122583D01*
Y-122417D01*
X323300Y-122333D01*
X323427Y-122417D01*
Y-122583D01*
X323300Y-122667D01*
G01Y-120417D02*
X323173Y-120333D01*
Y-120167D01*
X323300Y-120083D01*
X323427Y-120167D01*
Y-120333D01*
X323300Y-120417D01*
G01X296000Y-62500D02*
Y-137500D01*
G01X294000Y-62500D02*
Y-137500D01*
G01X301633Y-97500D02*
Y-92500D01*
X303153D01*
X303660Y-92750D01*
X304040Y-93333D01*
X304167Y-94000D01*
X304040Y-94667D01*
X303723Y-95167D01*
X303153Y-95417D01*
X301633D01*
G01X306860Y-97667D02*
X309140Y-92500D01*
G01X311643Y-97500D02*
Y-92500D01*
X314557Y-97500D01*
Y-92500D01*
G01X318200Y-97667D02*
X318073Y-97583D01*
Y-97417D01*
X318200Y-97333D01*
X318327Y-97417D01*
Y-97583D01*
X318200Y-97667D01*
G01Y-95417D02*
X318073Y-95333D01*
Y-95167D01*
X318200Y-95083D01*
X318327Y-95167D01*
Y-95333D01*
X318200Y-95417D01*
G01X296000Y-112500D02*
X496000D01*
G01X301633Y-72500D02*
Y-67500D01*
X303153D01*
X303660Y-67750D01*
X304040Y-68333D01*
X304167Y-69000D01*
X304040Y-69667D01*
X303723Y-70167D01*
X303153Y-70417D01*
X301633D01*
G01X306733Y-72500D02*
Y-67500D01*
X308317D01*
X308823Y-67750D01*
X309140Y-68083D01*
X309267Y-68750D01*
X309140Y-69417D01*
X308760Y-69833D01*
X308317Y-70083D01*
X306733D01*
G01X308317D02*
X309267Y-72500D01*
G01X313100D02*
X312593Y-72417D01*
X312150Y-72083D01*
X311770Y-71583D01*
X311517Y-71000D01*
X311390Y-70333D01*
Y-69667D01*
X311517Y-69000D01*
X311770Y-68417D01*
X312150Y-67917D01*
X312593Y-67583D01*
X313100Y-67500D01*
X313607Y-67583D01*
X314050Y-67917D01*
X314430Y-68417D01*
X314683Y-69000D01*
X314810Y-69667D01*
Y-70333D01*
X314683Y-71000D01*
X314430Y-71583D01*
X314050Y-72083D01*
X313607Y-72417D01*
X313100Y-72500D01*
G01X316933Y-71500D02*
X317250Y-72000D01*
X317630Y-72333D01*
X318073Y-72500D01*
X318580Y-72333D01*
X318960Y-72000D01*
X319340Y-71500D01*
X319467Y-70833D01*
Y-67500D01*
G01X324567Y-72500D02*
X322033D01*
Y-67500D01*
X324567D01*
G01X323553Y-69917D02*
X322033D01*
G01X329793Y-67917D02*
X329413Y-67667D01*
X328970Y-67500D01*
X328463D01*
X327893Y-67750D01*
X327450Y-68167D01*
X327133Y-68667D01*
X326880Y-69500D01*
X326817Y-70250D01*
X326943Y-71000D01*
X327133Y-71500D01*
X327513Y-72000D01*
X327957Y-72333D01*
X328400Y-72500D01*
X328843D01*
X329287Y-72333D01*
X329667Y-72083D01*
X329983Y-71750D01*
G01X333500Y-67500D02*
Y-72500D01*
G01X332043Y-67500D02*
X334957D01*
G01X338600Y-72667D02*
X338473Y-72583D01*
Y-72417D01*
X338600Y-72333D01*
X338727Y-72417D01*
Y-72583D01*
X338600Y-72667D01*
G01Y-70417D02*
X338473Y-70333D01*
Y-70167D01*
X338600Y-70083D01*
X338727Y-70167D01*
Y-70333D01*
X338600Y-70417D01*
G01X296000Y-87500D02*
X496000D01*
G01X411000Y-112500D02*
Y-137500D01*
G01X416633Y-122500D02*
Y-117500D01*
X418217D01*
X418723Y-117750D01*
X419040Y-118083D01*
X419167Y-118750D01*
X419040Y-119417D01*
X418660Y-119833D01*
X418217Y-120083D01*
X416633D01*
G01X418217D02*
X419167Y-122500D01*
G01X424267D02*
X421733D01*
Y-117500D01*
X424267D01*
G01X423253Y-119917D02*
X421733D01*
G01X426517Y-117500D02*
X428100Y-122500D01*
X429683Y-117500D01*
G01X433200Y-122667D02*
X433073Y-122583D01*
Y-122417D01*
X433200Y-122333D01*
X433327Y-122417D01*
Y-122583D01*
X433200Y-122667D01*
G01Y-120417D02*
X433073Y-120333D01*
Y-120167D01*
X433200Y-120083D01*
X433327Y-120167D01*
Y-120333D01*
X433200Y-120417D01*
G01X460000Y-112500D02*
Y-137500D01*
G01X-723776Y2987387D02*
Y-376795D01*
Y-489221D01*
X1782976D01*
Y-376795D01*
Y2987387D01*
X-723776D01*
G01X6705Y-124160D02*
X7332Y-124685D01*
X8037Y-125000D01*
X8663D01*
X9290Y-124685D01*
X9760Y-124160D01*
X9995Y-123425D01*
X9838Y-122690D01*
X9447Y-122060D01*
X8742Y-121640D01*
X7802Y-121430D01*
X7253Y-121010D01*
X7018Y-120275D01*
X7175Y-119540D01*
X7567Y-119015D01*
X8115Y-118700D01*
X8663D01*
X9212Y-118910D01*
X9682Y-119435D01*
G01X13005Y-125000D02*
Y-118700D01*
G01X16295D02*
Y-125000D01*
G01Y-121850D02*
X13005D01*
G01X20010Y-118700D02*
X21890D01*
G01X20950D02*
Y-125000D01*
G01X20010D02*
X21890D01*
G01X28817D02*
X25683D01*
Y-118700D01*
X28817D01*
G01X27563Y-121745D02*
X25683D01*
G01X31748Y-125000D02*
Y-118700D01*
X35352Y-125000D01*
Y-118700D01*
G01X39693Y-126155D02*
X40007Y-124790D01*
G01X46150Y-118700D02*
Y-125000D01*
G01X44348Y-118700D02*
X47952D01*
G01X50492Y-125000D02*
X52450Y-118700D01*
X54408Y-125000D01*
G01X53703Y-122795D02*
X51197D01*
G01X57810Y-118700D02*
X59690D01*
G01X58750D02*
Y-125000D01*
G01X57810D02*
X59690D01*
G01X62700Y-118700D02*
X63797Y-125000D01*
X65050Y-118700D01*
X66303Y-125000D01*
X67400Y-118700D01*
G01X69392Y-125000D02*
X71350Y-118700D01*
X73308Y-125000D01*
G01X72603Y-122795D02*
X70097D01*
G01X75848Y-125000D02*
Y-118700D01*
X79452Y-125000D01*
Y-118700D01*
G01X88683Y-125000D02*
Y-118700D01*
X90642D01*
X91268Y-119015D01*
X91660Y-119435D01*
X91817Y-120275D01*
X91660Y-121115D01*
X91190Y-121640D01*
X90642Y-121955D01*
X88683D01*
G01X90642D02*
X91817Y-125000D01*
G01X96550Y-125210D02*
X96393Y-125105D01*
Y-124895D01*
X96550Y-124790D01*
X96707Y-124895D01*
Y-125105D01*
X96550Y-125210D01*
G01X102850Y-125000D02*
X102223Y-124895D01*
X101675Y-124475D01*
X101205Y-123845D01*
X100892Y-123110D01*
X100735Y-122270D01*
Y-121430D01*
X100892Y-120590D01*
X101205Y-119855D01*
X101675Y-119225D01*
X102223Y-118805D01*
X102850Y-118700D01*
X103477Y-118805D01*
X104025Y-119225D01*
X104495Y-119855D01*
X104808Y-120590D01*
X104965Y-121430D01*
Y-122270D01*
X104808Y-123110D01*
X104495Y-123845D01*
X104025Y-124475D01*
X103477Y-124895D01*
X102850Y-125000D01*
G01X109150Y-125210D02*
X108993Y-125105D01*
Y-124895D01*
X109150Y-124790D01*
X109307Y-124895D01*
Y-125105D01*
X109150Y-125210D01*
G01X117173Y-119225D02*
X116703Y-118910D01*
X116155Y-118700D01*
X115528D01*
X114823Y-119015D01*
X114275Y-119540D01*
X113883Y-120170D01*
X113570Y-121220D01*
X113492Y-122165D01*
X113648Y-123110D01*
X113883Y-123740D01*
X114353Y-124370D01*
X114902Y-124790D01*
X115450Y-125000D01*
X115998D01*
X116547Y-124790D01*
X117017Y-124475D01*
X117408Y-124055D01*
G01X121750Y-125210D02*
X121593Y-125105D01*
Y-124895D01*
X121750Y-124790D01*
X121907Y-124895D01*
Y-125105D01*
X121750Y-125210D01*
G01X6627Y-115000D02*
Y-108700D01*
G01X9603D02*
X6627Y-112585D01*
G01X10073Y-115000D02*
X7958Y-110800D01*
G01X12927Y-108700D02*
Y-113215D01*
X13240Y-114160D01*
X13867Y-114790D01*
X14650Y-115000D01*
X15433Y-114790D01*
X16060Y-114160D01*
X16373Y-113215D01*
Y-108700D01*
G01X22517Y-115000D02*
X19383D01*
Y-108700D01*
X22517D01*
G01X21263Y-111745D02*
X19383D01*
G01X26310Y-108700D02*
X28190D01*
G01X27250D02*
Y-115000D01*
G01X26310D02*
X28190D01*
G01X38205Y-114160D02*
X38832Y-114685D01*
X39537Y-115000D01*
X40163D01*
X40790Y-114685D01*
X41260Y-114160D01*
X41495Y-113425D01*
X41338Y-112690D01*
X40947Y-112060D01*
X40242Y-111640D01*
X39302Y-111430D01*
X38753Y-111010D01*
X38518Y-110275D01*
X38675Y-109540D01*
X39067Y-109015D01*
X39615Y-108700D01*
X40163D01*
X40712Y-108910D01*
X41182Y-109435D01*
G01X44505Y-115000D02*
Y-108700D01*
G01X47795D02*
Y-115000D01*
G01Y-111850D02*
X44505D01*
G01X50492Y-115000D02*
X52450Y-108700D01*
X54408Y-115000D01*
G01X53703Y-112795D02*
X51197D01*
G01X56948Y-115000D02*
Y-108700D01*
X60552Y-115000D01*
Y-108700D01*
G01X69705Y-115000D02*
Y-108700D01*
G01X72995D02*
Y-115000D01*
G01Y-111850D02*
X69705D01*
G01X76005Y-114160D02*
X76632Y-114685D01*
X77337Y-115000D01*
X77963D01*
X78590Y-114685D01*
X79060Y-114160D01*
X79295Y-113425D01*
X79138Y-112690D01*
X78747Y-112060D01*
X78042Y-111640D01*
X77102Y-111430D01*
X76553Y-111010D01*
X76318Y-110275D01*
X76475Y-109540D01*
X76867Y-109015D01*
X77415Y-108700D01*
X77963D01*
X78512Y-108910D01*
X78982Y-109435D01*
G01X83010Y-108700D02*
X84890D01*
G01X83950D02*
Y-115000D01*
G01X83010D02*
X84890D01*
G01X88292D02*
X90250Y-108700D01*
X92208Y-115000D01*
G01X91503Y-112795D02*
X88997D01*
G01X94748Y-115000D02*
Y-108700D01*
X98352Y-115000D01*
Y-108700D01*
G01X103320Y-111850D02*
X104887D01*
Y-113740D01*
X104417Y-114370D01*
X103868Y-114790D01*
X103085Y-115000D01*
X102302Y-114790D01*
X101753Y-114370D01*
X101283Y-113740D01*
X100970Y-113005D01*
X100813Y-112165D01*
Y-111430D01*
X100970Y-110800D01*
X101283Y-110065D01*
X101753Y-109435D01*
X102223Y-109015D01*
X102850Y-108700D01*
X103398D01*
X104025Y-108910D01*
X104495Y-109330D01*
G01X108993Y-116155D02*
X109307Y-114790D01*
G01X115450Y-108700D02*
Y-115000D01*
G01X113648Y-108700D02*
X117252D01*
G01X119792Y-115000D02*
X121750Y-108700D01*
X123708Y-115000D01*
G01X123003Y-112795D02*
X120497D01*
G01X128050Y-115000D02*
X127423Y-114895D01*
X126875Y-114475D01*
X126405Y-113845D01*
X126092Y-113110D01*
X125935Y-112270D01*
Y-111430D01*
X126092Y-110590D01*
X126405Y-109855D01*
X126875Y-109225D01*
X127423Y-108805D01*
X128050Y-108700D01*
X128677Y-108805D01*
X129225Y-109225D01*
X129695Y-109855D01*
X130008Y-110590D01*
X130165Y-111430D01*
Y-112270D01*
X130008Y-113110D01*
X129695Y-113845D01*
X129225Y-114475D01*
X128677Y-114895D01*
X128050Y-115000D01*
G01X140650D02*
Y-112165D01*
X139083Y-108700D01*
G01X142217D02*
X140650Y-112165D01*
G01X145227Y-108700D02*
Y-113215D01*
X145540Y-114160D01*
X146167Y-114790D01*
X146950Y-115000D01*
X147733Y-114790D01*
X148360Y-114160D01*
X148673Y-113215D01*
Y-108700D01*
G01X151292Y-115000D02*
X153250Y-108700D01*
X155208Y-115000D01*
G01X154503Y-112795D02*
X151997D01*
G01X157748Y-115000D02*
Y-108700D01*
X161352Y-115000D01*
Y-108700D01*
G01X30650Y-92300D02*
X28130Y-91883D01*
X25925Y-90217D01*
X24035Y-87717D01*
X22775Y-84800D01*
X22145Y-81467D01*
Y-78133D01*
X22775Y-74800D01*
X24035Y-71883D01*
X25925Y-69384D01*
X28130Y-67717D01*
X30650Y-67300D01*
X33170Y-67717D01*
X35375Y-69384D01*
X37265Y-71883D01*
X38525Y-74800D01*
X39155Y-78133D01*
Y-81467D01*
X38525Y-84800D01*
X37265Y-87717D01*
X35375Y-90217D01*
X33170Y-91883D01*
X30650Y-92300D01*
G01X33170Y-85633D02*
X36950Y-92300D01*
G01X50495Y-75634D02*
Y-87300D01*
X51755Y-90217D01*
X53645Y-91883D01*
X55850Y-92300D01*
X58055Y-91883D01*
X59945Y-90217D01*
X61205Y-87300D01*
G01Y-92300D02*
Y-75634D01*
G01X86720Y-92300D02*
Y-75634D01*
G01Y-78550D02*
X85460Y-76884D01*
X83570Y-76050D01*
X81365Y-75634D01*
X79160Y-76467D01*
X77270Y-78133D01*
X76010Y-80634D01*
X75380Y-83967D01*
X76010Y-87300D01*
X77270Y-89801D01*
X79160Y-91467D01*
X81365Y-92300D01*
X83570Y-91883D01*
X85460Y-90634D01*
X86720Y-88967D01*
G01X100895Y-92300D02*
Y-75634D01*
G01Y-79800D02*
X102155Y-77717D01*
X104045Y-76050D01*
X106565Y-75634D01*
X108770Y-76050D01*
X110660Y-77717D01*
X111605Y-80634D01*
Y-92300D01*
G01X131450Y-67300D02*
Y-92300D01*
G01X127040Y-75634D02*
X135860D01*
G01X162320Y-92300D02*
Y-75634D01*
G01Y-78550D02*
X161060Y-76884D01*
X159170Y-76050D01*
X156965Y-75634D01*
X154760Y-76467D01*
X152870Y-78133D01*
X151610Y-80634D01*
X150980Y-83967D01*
X151610Y-87300D01*
X152870Y-89801D01*
X154760Y-91467D01*
X156965Y-92300D01*
X159170Y-91883D01*
X161060Y-90634D01*
X162320Y-88967D01*
G01X6548Y-105000D02*
Y-98700D01*
X10152Y-105000D01*
Y-98700D01*
G01X14650Y-105000D02*
X14023Y-104895D01*
X13475Y-104475D01*
X13005Y-103845D01*
X12692Y-103110D01*
X12535Y-102270D01*
Y-101430D01*
X12692Y-100590D01*
X13005Y-99855D01*
X13475Y-99225D01*
X14023Y-98805D01*
X14650Y-98700D01*
X15277Y-98805D01*
X15825Y-99225D01*
X16295Y-99855D01*
X16608Y-100590D01*
X16765Y-101430D01*
Y-102270D01*
X16608Y-103110D01*
X16295Y-103845D01*
X15825Y-104475D01*
X15277Y-104895D01*
X14650Y-105000D01*
G01X20950Y-105210D02*
X20793Y-105105D01*
Y-104895D01*
X20950Y-104790D01*
X21107Y-104895D01*
Y-105105D01*
X20950Y-105210D01*
G01X27250Y-105000D02*
Y-98700D01*
X26310Y-99960D01*
G01Y-105000D02*
X28190D01*
G01X33550D02*
X34098Y-104895D01*
X34725Y-104580D01*
X35117Y-104055D01*
X35273Y-103320D01*
X35117Y-102585D01*
X34647Y-101955D01*
X33942Y-101640D01*
X33158D01*
X32688Y-101430D01*
X32297Y-100905D01*
X32140Y-100170D01*
X32375Y-99435D01*
X32923Y-98910D01*
X33550Y-98700D01*
X34177Y-98910D01*
X34725Y-99435D01*
X34960Y-100170D01*
X34803Y-100905D01*
X34412Y-101430D01*
X33942Y-101640D01*
X33158D01*
X32453Y-101955D01*
X31983Y-102585D01*
X31827Y-103320D01*
X31983Y-104055D01*
X32375Y-104580D01*
X33002Y-104895D01*
X33550Y-105000D01*
G01X39850D02*
X40398Y-104895D01*
X41025Y-104580D01*
X41417Y-104055D01*
X41573Y-103320D01*
X41417Y-102585D01*
X40947Y-101955D01*
X40242Y-101640D01*
X39458D01*
X38988Y-101430D01*
X38597Y-100905D01*
X38440Y-100170D01*
X38675Y-99435D01*
X39223Y-98910D01*
X39850Y-98700D01*
X40477Y-98910D01*
X41025Y-99435D01*
X41260Y-100170D01*
X41103Y-100905D01*
X40712Y-101430D01*
X40242Y-101640D01*
X39458D01*
X38753Y-101955D01*
X38283Y-102585D01*
X38127Y-103320D01*
X38283Y-104055D01*
X38675Y-104580D01*
X39302Y-104895D01*
X39850Y-105000D01*
G01X45993Y-106155D02*
X46307Y-104790D01*
G01X50100Y-98700D02*
X51197Y-105000D01*
X52450Y-98700D01*
X53703Y-105000D01*
X54800Y-98700D01*
G01X60317Y-105000D02*
X57183D01*
Y-98700D01*
X60317D01*
G01X59063Y-101745D02*
X57183D01*
G01X63248Y-105000D02*
Y-98700D01*
X66852Y-105000D01*
Y-98700D01*
G01X76005Y-105000D02*
Y-98700D01*
G01X79295D02*
Y-105000D01*
G01Y-101850D02*
X76005D01*
G01X81600Y-98700D02*
X82697Y-105000D01*
X83950Y-98700D01*
X85203Y-105000D01*
X86300Y-98700D01*
G01X88292Y-105000D02*
X90250Y-98700D01*
X92208Y-105000D01*
G01X91503Y-102795D02*
X88997D01*
G01X101362Y-99750D02*
X101832Y-99120D01*
X102380Y-98805D01*
X103007Y-98700D01*
X103790Y-98910D01*
X104338Y-99435D01*
X104495Y-100065D01*
X104417Y-100695D01*
X104103Y-101220D01*
X102537Y-102270D01*
X101832Y-103005D01*
X101362Y-104055D01*
X101205Y-105000D01*
X104495D01*
G01X107348D02*
Y-98700D01*
X110952Y-105000D01*
Y-98700D01*
G01X113727Y-105000D02*
Y-98700D01*
X115293D01*
X115920Y-99015D01*
X116390Y-99435D01*
X116782Y-100065D01*
X117095Y-100800D01*
X117173Y-101850D01*
X117095Y-102900D01*
X116782Y-103635D01*
X116390Y-104265D01*
X115920Y-104685D01*
X115293Y-105000D01*
X113727D01*
G01X126483D02*
Y-98700D01*
X128442D01*
X129068Y-99015D01*
X129460Y-99435D01*
X129617Y-100275D01*
X129460Y-101115D01*
X128990Y-101640D01*
X128442Y-101955D01*
X126483D01*
G01X128442D02*
X129617Y-105000D01*
G01X132627D02*
Y-98700D01*
X134193D01*
X134820Y-99015D01*
X135290Y-99435D01*
X135682Y-100065D01*
X135995Y-100800D01*
X136073Y-101850D01*
X135995Y-102900D01*
X135682Y-103635D01*
X135290Y-104265D01*
X134820Y-104685D01*
X134193Y-105000D01*
X132627D01*
G01X140650Y-105210D02*
X140493Y-105105D01*
Y-104895D01*
X140650Y-104790D01*
X140807Y-104895D01*
Y-105105D01*
X140650Y-105210D01*
G01X202000Y-72000D02*
Y-80000D01*
X206000D01*
G01X213800D02*
Y-74667D01*
G01Y-75600D02*
X213400Y-75067D01*
X212800Y-74800D01*
X212100Y-74667D01*
X211400Y-74933D01*
X210800Y-75467D01*
X210400Y-76267D01*
X210200Y-77333D01*
X210400Y-78400D01*
X210800Y-79200D01*
X211400Y-79733D01*
X212100Y-80000D01*
X212800Y-79867D01*
X213400Y-79467D01*
X213800Y-78934D01*
G01X217900Y-82400D02*
X218500Y-82667D01*
X219300Y-82400D01*
X219800Y-81867D01*
X220200Y-81200D01*
X220800Y-79067D01*
X222100Y-74667D01*
G01X218900D02*
X220800Y-79067D01*
G01X226500Y-76400D02*
X229700D01*
X229400Y-75467D01*
X228900Y-74933D01*
X228200Y-74667D01*
X227500Y-74800D01*
X226900Y-75200D01*
X226500Y-76133D01*
X226300Y-76934D01*
Y-77733D01*
X226500Y-78533D01*
X227000Y-79333D01*
X227600Y-79867D01*
X228300Y-80000D01*
X229000Y-79733D01*
X229700Y-78934D01*
G01X234600Y-80000D02*
Y-74667D01*
G01Y-75733D02*
X235100Y-75200D01*
X235600Y-74800D01*
X236300Y-74667D01*
X236800Y-74800D01*
X237400Y-75200D01*
G01X223400Y-128934D02*
X224200Y-129600D01*
X225100Y-130000D01*
X225900D01*
X226700Y-129600D01*
X227300Y-128934D01*
X227600Y-128000D01*
X227400Y-127067D01*
X226900Y-126267D01*
X226000Y-125733D01*
X224800Y-125467D01*
X224100Y-124933D01*
X223800Y-124000D01*
X224000Y-123067D01*
X224500Y-122400D01*
X225200Y-122000D01*
X225900D01*
X226600Y-122267D01*
X227200Y-122933D01*
G01X235300Y-130000D02*
Y-124667D01*
G01Y-125600D02*
X234900Y-125067D01*
X234300Y-124800D01*
X233600Y-124667D01*
X232900Y-124933D01*
X232300Y-125467D01*
X231900Y-126267D01*
X231700Y-127333D01*
X231900Y-128400D01*
X232300Y-129200D01*
X232900Y-129733D01*
X233600Y-130000D01*
X234300Y-129867D01*
X234900Y-129467D01*
X235300Y-128934D01*
G01X239800Y-130000D02*
Y-124667D01*
G01Y-126000D02*
X240200Y-125333D01*
X240800Y-124800D01*
X241600Y-124667D01*
X242300Y-124800D01*
X242900Y-125333D01*
X243200Y-126267D01*
Y-130000D01*
G01X251300Y-122000D02*
Y-130000D01*
G01Y-128800D02*
X250900Y-129467D01*
X250300Y-129867D01*
X249600Y-130000D01*
X248800Y-129733D01*
X248200Y-129067D01*
X247800Y-128267D01*
X247700Y-127333D01*
X247800Y-126400D01*
X248200Y-125600D01*
X248800Y-124933D01*
X249600Y-124667D01*
X250300Y-124800D01*
X250800Y-125067D01*
X251300Y-125600D01*
G01X255400Y-132400D02*
X256000Y-132667D01*
X256800Y-132400D01*
X257300Y-131867D01*
X257700Y-131200D01*
X258300Y-129067D01*
X259600Y-124667D01*
G01X256400D02*
X258300Y-129067D01*
G01X230500Y-97000D02*
X233000Y-105000D01*
X235500Y-97000D01*
G01X243200Y-97667D02*
X242600Y-97267D01*
X241900Y-97000D01*
X241100D01*
X240200Y-97400D01*
X239500Y-98067D01*
X239000Y-98867D01*
X238600Y-100200D01*
X238500Y-101400D01*
X238700Y-102600D01*
X239000Y-103400D01*
X239600Y-104200D01*
X240300Y-104733D01*
X241000Y-105000D01*
X241700D01*
X242400Y-104733D01*
X243000Y-104333D01*
X243500Y-103800D01*
G01X251200Y-97667D02*
X250600Y-97267D01*
X249900Y-97000D01*
X249100D01*
X248200Y-97400D01*
X247500Y-98067D01*
X247000Y-98867D01*
X246600Y-100200D01*
X246500Y-101400D01*
X246700Y-102600D01*
X247000Y-103400D01*
X247600Y-104200D01*
X248300Y-104733D01*
X249000Y-105000D01*
X249700D01*
X250400Y-104733D01*
X251000Y-104333D01*
X251500Y-103800D01*
G01X256700Y-80000D02*
Y-72000D01*
X253000Y-77733D01*
X258000D01*
G01X328600Y-123333D02*
X329200Y-122533D01*
X329900Y-122133D01*
X330700Y-122000D01*
X331700Y-122267D01*
X332400Y-122933D01*
X332600Y-123733D01*
X332500Y-124534D01*
X332100Y-125200D01*
X330100Y-126533D01*
X329200Y-127467D01*
X328600Y-128800D01*
X328400Y-130000D01*
X332600D01*
G01X338500Y-122000D02*
X337700Y-122267D01*
X337100Y-122933D01*
X336700Y-123733D01*
X336400Y-124800D01*
X336300Y-126000D01*
X336400Y-127200D01*
X336700Y-128267D01*
X337100Y-129067D01*
X337700Y-129733D01*
X338500Y-130000D01*
X339300Y-129733D01*
X339900Y-129067D01*
X340300Y-128267D01*
X340600Y-127200D01*
X340700Y-126000D01*
X340600Y-124800D01*
X340300Y-123733D01*
X339900Y-122933D01*
X339300Y-122267D01*
X338500Y-122000D01*
G01X346500Y-130000D02*
Y-122000D01*
X345300Y-123600D01*
G01Y-130000D02*
X347700D01*
G01X352600Y-123333D02*
X353200Y-122533D01*
X353900Y-122133D01*
X354700Y-122000D01*
X355700Y-122267D01*
X356400Y-122933D01*
X356600Y-123733D01*
X356500Y-124534D01*
X356100Y-125200D01*
X354100Y-126533D01*
X353200Y-127467D01*
X352600Y-128800D01*
X352400Y-130000D01*
X356600D01*
G01X360700Y-130267D02*
X364300Y-122000D01*
G01X370500D02*
X369700Y-122267D01*
X369100Y-122933D01*
X368700Y-123733D01*
X368400Y-124800D01*
X368300Y-126000D01*
X368400Y-127200D01*
X368700Y-128267D01*
X369100Y-129067D01*
X369700Y-129733D01*
X370500Y-130000D01*
X371300Y-129733D01*
X371900Y-129067D01*
X372300Y-128267D01*
X372600Y-127200D01*
X372700Y-126000D01*
X372600Y-124800D01*
X372300Y-123733D01*
X371900Y-122933D01*
X371300Y-122267D01*
X370500Y-122000D01*
G01X376800Y-129067D02*
X377500Y-129733D01*
X378300Y-130000D01*
X379100Y-129733D01*
X379800Y-128934D01*
X380300Y-127733D01*
X380500Y-126533D01*
Y-125067D01*
X380300Y-123867D01*
X379800Y-122800D01*
X379200Y-122267D01*
X378500Y-122000D01*
X377700Y-122267D01*
X377100Y-122800D01*
X376700Y-123600D01*
X376500Y-124667D01*
X376700Y-125600D01*
X377200Y-126533D01*
X377800Y-127067D01*
X378500Y-127200D01*
X379300Y-126934D01*
X379900Y-126267D01*
X380500Y-125067D01*
G01X384700Y-130267D02*
X388300Y-122000D01*
G01X392600Y-123333D02*
X393200Y-122533D01*
X393900Y-122133D01*
X394700Y-122000D01*
X395700Y-122267D01*
X396400Y-122933D01*
X396600Y-123733D01*
X396500Y-124534D01*
X396100Y-125200D01*
X394100Y-126533D01*
X393200Y-127467D01*
X392600Y-128800D01*
X392400Y-130000D01*
X396600D01*
G01X402500D02*
X403200Y-129867D01*
X404000Y-129467D01*
X404500Y-128800D01*
X404700Y-127867D01*
X404500Y-126934D01*
X403900Y-126133D01*
X403000Y-125733D01*
X402000D01*
X401400Y-125467D01*
X400900Y-124800D01*
X400700Y-123867D01*
X401000Y-122933D01*
X401700Y-122267D01*
X402500Y-122000D01*
X403300Y-122267D01*
X404000Y-122933D01*
X404300Y-123867D01*
X404100Y-124800D01*
X403600Y-125467D01*
X403000Y-125733D01*
X402000D01*
X401100Y-126133D01*
X400500Y-126934D01*
X400300Y-127867D01*
X400500Y-128800D01*
X401000Y-129467D01*
X401800Y-129867D01*
X402500Y-130000D01*
G01X328300Y-105000D02*
Y-97000D01*
X330300D01*
X331100Y-97400D01*
X331700Y-97933D01*
X332200Y-98733D01*
X332600Y-99667D01*
X332700Y-101000D01*
X332600Y-102333D01*
X332200Y-103267D01*
X331700Y-104067D01*
X331100Y-104600D01*
X330300Y-105000D01*
X328300D01*
G01X336000D02*
X338500Y-97000D01*
X341000Y-105000D01*
G01X340100Y-102200D02*
X336900D01*
G01X346500Y-97000D02*
X345700Y-97267D01*
X345100Y-97933D01*
X344700Y-98733D01*
X344400Y-99800D01*
X344300Y-101000D01*
X344400Y-102200D01*
X344700Y-103267D01*
X345100Y-104067D01*
X345700Y-104733D01*
X346500Y-105000D01*
X347300Y-104733D01*
X347900Y-104067D01*
X348300Y-103267D01*
X348600Y-102200D01*
X348700Y-101000D01*
X348600Y-99800D01*
X348300Y-98733D01*
X347900Y-97933D01*
X347300Y-97267D01*
X346500Y-97000D01*
G01X354500D02*
Y-105000D01*
G01X352200Y-97000D02*
X356800D01*
G01X360600Y-101667D02*
X361300Y-100733D01*
X361900Y-100200D01*
X362700Y-99933D01*
X363400Y-100200D01*
X363900Y-100733D01*
X364300Y-101533D01*
X364400Y-102467D01*
X364300Y-103267D01*
X363900Y-104067D01*
X363300Y-104733D01*
X362600Y-105000D01*
X361800Y-104733D01*
X361100Y-103934D01*
X360700Y-102733D01*
X360600Y-101400D01*
X360800Y-99667D01*
X361100Y-98733D01*
X361600Y-97800D01*
X362300Y-97133D01*
X363000Y-97000D01*
X363700Y-97267D01*
X364200Y-97933D01*
G01X367900Y-105000D02*
Y-97000D01*
X370500Y-103667D01*
X373100Y-97000D01*
Y-105000D01*
G01X378500Y-97000D02*
Y-105000D01*
G01X376200Y-97000D02*
X380800D01*
G01X387300Y-100733D02*
X387700Y-100333D01*
X388000Y-99667D01*
X388200Y-98733D01*
X388000Y-97933D01*
X387600Y-97400D01*
X386900Y-97000D01*
X384200D01*
Y-105000D01*
X387500D01*
X388200Y-104467D01*
X388600Y-103667D01*
X388800Y-102733D01*
X388600Y-101800D01*
X388000Y-101000D01*
X387300Y-100733D01*
X384200D01*
G01X394500Y-105000D02*
X395200Y-104867D01*
X396000Y-104467D01*
X396500Y-103800D01*
X396700Y-102867D01*
X396500Y-101934D01*
X395900Y-101133D01*
X395000Y-100733D01*
X394000D01*
X393400Y-100467D01*
X392900Y-99800D01*
X392700Y-98867D01*
X393000Y-97933D01*
X393700Y-97267D01*
X394500Y-97000D01*
X395300Y-97267D01*
X396000Y-97933D01*
X396300Y-98867D01*
X396100Y-99800D01*
X395600Y-100467D01*
X395000Y-100733D01*
X394000D01*
X393100Y-101133D01*
X392500Y-101934D01*
X392300Y-102867D01*
X392500Y-103800D01*
X393000Y-104467D01*
X393800Y-104867D01*
X394500Y-105000D01*
G01X400300D02*
Y-97000D01*
X402300D01*
X403100Y-97400D01*
X403700Y-97933D01*
X404200Y-98733D01*
X404600Y-99667D01*
X404700Y-101000D01*
X404600Y-102333D01*
X404200Y-103267D01*
X403700Y-104067D01*
X403100Y-104600D01*
X402300Y-105000D01*
X400300D01*
G01X410500Y-97000D02*
X409700Y-97267D01*
X409100Y-97933D01*
X408700Y-98733D01*
X408400Y-99800D01*
X408300Y-101000D01*
X408400Y-102200D01*
X408700Y-103267D01*
X409100Y-104067D01*
X409700Y-104733D01*
X410500Y-105000D01*
X411300Y-104733D01*
X411900Y-104067D01*
X412300Y-103267D01*
X412600Y-102200D01*
X412700Y-101000D01*
X412600Y-99800D01*
X412300Y-98733D01*
X411900Y-97933D01*
X411300Y-97267D01*
X410500Y-97000D01*
G01X350500Y-72000D02*
Y-80000D01*
G01X348200Y-72000D02*
X352800D01*
G01X356600Y-76667D02*
X357300Y-75733D01*
X357900Y-75200D01*
X358700Y-74933D01*
X359400Y-75200D01*
X359900Y-75733D01*
X360300Y-76533D01*
X360400Y-77467D01*
X360300Y-78267D01*
X359900Y-79067D01*
X359300Y-79733D01*
X358600Y-80000D01*
X357800Y-79733D01*
X357100Y-78934D01*
X356700Y-77733D01*
X356600Y-76400D01*
X356800Y-74667D01*
X357100Y-73733D01*
X357600Y-72800D01*
X358300Y-72133D01*
X359000Y-72000D01*
X359700Y-72267D01*
X360200Y-72933D01*
G01X363900Y-80000D02*
Y-72000D01*
X366500Y-78667D01*
X369100Y-72000D01*
Y-80000D01*
G01X371500Y-82667D02*
X377500D01*
G01X380500Y-80000D02*
Y-72000D01*
X382900D01*
X383700Y-72400D01*
X384300Y-73333D01*
X384500Y-74400D01*
X384300Y-75467D01*
X383800Y-76267D01*
X382900Y-76667D01*
X380500D01*
G01X388300Y-80000D02*
Y-72000D01*
X390300D01*
X391100Y-72400D01*
X391700Y-72933D01*
X392200Y-73733D01*
X392600Y-74667D01*
X392700Y-76000D01*
X392600Y-77333D01*
X392200Y-78267D01*
X391700Y-79067D01*
X391100Y-79600D01*
X390300Y-80000D01*
X388300D01*
G01X399300Y-75733D02*
X399700Y-75333D01*
X400000Y-74667D01*
X400200Y-73733D01*
X400000Y-72933D01*
X399600Y-72400D01*
X398900Y-72000D01*
X396200D01*
Y-80000D01*
X399500D01*
X400200Y-79467D01*
X400600Y-78667D01*
X400800Y-77733D01*
X400600Y-76800D01*
X400000Y-76000D01*
X399300Y-75733D01*
X396200D01*
G01X403500Y-82667D02*
X409500D01*
G01X412300Y-80000D02*
Y-72000D01*
X414300D01*
X415100Y-72400D01*
X415700Y-72933D01*
X416200Y-73733D01*
X416600Y-74667D01*
X416700Y-76000D01*
X416600Y-77333D01*
X416200Y-78267D01*
X415700Y-79067D01*
X415100Y-79600D01*
X414300Y-80000D01*
X412300D01*
G01X419500Y-82667D02*
X425500D01*
G01X431300Y-75733D02*
X431700Y-75333D01*
X432000Y-74667D01*
X432200Y-73733D01*
X432000Y-72933D01*
X431600Y-72400D01*
X430900Y-72000D01*
X428200D01*
Y-80000D01*
X431500D01*
X432200Y-79467D01*
X432600Y-78667D01*
X432800Y-77733D01*
X432600Y-76800D01*
X432000Y-76000D01*
X431300Y-75733D01*
X428200D01*
G01X436300Y-80000D02*
Y-72000D01*
X438300D01*
X439100Y-72400D01*
X439700Y-72933D01*
X440200Y-73733D01*
X440600Y-74667D01*
X440700Y-76000D01*
X440600Y-77333D01*
X440200Y-78267D01*
X439700Y-79067D01*
X439100Y-79600D01*
X438300Y-80000D01*
X436300D01*
G01X443300Y-130000D02*
Y-122000D01*
X445300D01*
X446100Y-122400D01*
X446700Y-122933D01*
X447200Y-123733D01*
X447600Y-124667D01*
X447700Y-126000D01*
X447600Y-127333D01*
X447200Y-128267D01*
X446700Y-129067D01*
X446100Y-129600D01*
X445300Y-130000D01*
X443300D01*
G01X473000D02*
Y-122000D01*
X471800Y-123600D01*
G01Y-130000D02*
X474200D01*
G01X478800Y-128800D02*
X479400Y-129467D01*
X480100Y-129867D01*
X481000Y-130000D01*
X481900Y-129733D01*
X482600Y-129200D01*
X483100Y-128267D01*
X483200Y-127200D01*
X483000Y-126133D01*
X482500Y-125467D01*
X481800Y-124933D01*
X481100Y-124800D01*
X480400Y-124933D01*
X479500Y-125467D01*
X479800Y-122000D01*
X482500D01*
M02*
